FILE_TYPE = MACRO_DRAWING;
SET COLOR_WIRE YELLOW;
SET COLOR_PROP ORANGE;
SET COLOR_DOT WHITE;
SET COLOR_ARC YELLOW;
SET COLOR_BODY GREEN;
SET COLOR_NOTE PURPLE;
SET PROP_DISPLAY VALUE;
SET PAGE_NUMBER P50;
SET PATH_NUMBER P295;
FORCEADD UNIVERSAL_GND..1
(-3175 2925);
FORCEPROP 3 LASTPIN (-3175 2975) SIG_NAME GND\g
J 0
(-3165 2985);
DISPLAY 0.659574 (-3165 2985);
PAINT MONO (-3165 2985);
DISPLAY INVISIBLE (-3165 2985);
FORCEPROP 2 LAST CDS_LIB logical_power
J 0
(-3175 2925);
DISPLAY INVISIBLE (-3175 2925);
FORCEPROP 1 LAST HDL_POWER GND
J 1
(-3150 2850);
DISPLAY 0.702128 (-3150 2850);
PAINT GREEN (-3150 2850);
DISPLAY INVISIBLE (-3150 2850);
FORCEPROP 1 LAST PATH I138
J 0
(-3100 2925);
DISPLAY 0.872340 (-3100 2925);
PAINT AQUA (-3100 2925);
DISPLAY INVISIBLE (-3100 2925);
FORCEADD 74LVC1G07GW..1
(-125 4650);
FORCEPROP 2 LAST VALUE 74LVC1G07GW
J 0
(-300 4975);
DISPLAY 0.510638 (-300 4975);
PAINT SKYBLUE (-300 4975);
FORCEPROP 2 LAST PART_TYPE SMLF
J 0
(-300 5025);
DISPLAY 0.510638 (-300 5025);
PAINT SKYBLUE (-300 5025);
FORCEPROP 1 LAST PART_NUMBER ALVC1G07002
J 0
(-300 4875);
DISPLAY 0.510638 (-300 4875);
PAINT WHITE (-300 4875);
FORCEPROP 1 LAST MATERIAL IC
J 0
(-300 4825);
DISPLAY 0.510638 (-300 4825);
PAINT SKYBLUE (-300 4825);
FORCEPROP 2 LAST SEC_TYPE 
J 0
(-300 5050);
DISPLAY 1.021277 (-300 5050);
DISPLAY INVISIBLE (-300 5050);
FORCEPROP 1 LAST CDS_LMAN_SYM_OUTLINE -150,150,150,-150
J 0
(-125 4650);
DISPLAY 0.468085 (-125 4650);
PAINT GREEN (-125 4650);
DISPLAY INVISIBLE (-125 4650);
FORCEPROP 2 LAST CDS_LIB pure_quanta
J 0
(-125 4650);
DISPLAY INVISIBLE (-125 4650);
FORCEPROP 1 LAST PATH I151
J 0
(-125 4650);
DISPLAY 0.723404 (-125 4650);
PAINT GREEN (-125 4650);
DISPLAY INVISIBLE (-125 4650);
FORCEPROP 1 LAST LOCATION U31
J 0
(-300 4925);
DISPLAY 0.702128 (-300 4925);
PAINT YELLOW (-300 4925);
FORCEPROP 0 LASTPIN (-325 4650) $PN 2
J 2
(-335 4660);
DISPLAY 0.680851 (-335 4660);
PAINT MONO (-335 4660);
FORCEPROP 0 LASTPIN (-325 4550) $PN 3
J 2
(-335 4560);
DISPLAY 0.680851 (-335 4560);
PAINT MONO (-335 4560);
FORCEPROP 0 LASTPIN (75 4550) $PN 1
J 0
(85 4560);
DISPLAY 0.680851 (85 4560);
PAINT MONO (85 4560);
FORCEPROP 0 LASTPIN (-325 4750) $PN 5
J 2
(-335 4760);
DISPLAY 0.680851 (-335 4760);
PAINT MONO (-335 4760);
FORCEPROP 0 LASTPIN (75 4650) $PN 4
J 0
(85 4660);
DISPLAY 0.680851 (85 4660);
PAINT MONO (85 4660);
FORCEPROP 2 LAST SEC 1
J 0
(-300 5050);
DISPLAY 0.680851 (-300 5050);
PAINT MONO (-300 5050);
DISPLAY INVISIBLE (-300 5050);
FORCEADD Q_RES..1
R 2
(-2000 5175);
FORCEPROP 1 LAST MATERIAL CHIP
J 2
(-1725 5150);
DISPLAY 0.510638 (-1725 5150);
PAINT SKYBLUE (-1725 5150);
FORCEPROP 1 LAST VALUE 0
J 0
(-1950 5150);
DISPLAY 0.510638 (-1950 5150);
PAINT SKYBLUE (-1950 5150);
FORCEPROP 1 LAST PACK_TYPE 0402LF
J 2
(-1400 5150);
DISPLAY 0.510638 (-1400 5150);
PAINT SKYBLUE (-1400 5150);
DISPLAY INVISIBLE (-1400 5150);
FORCEPROP 1 LAST WATTAGE 1/16W
J 0
(-1700 5150);
DISPLAY 0.510638 (-1700 5150);
PAINT SKYBLUE (-1700 5150);
DISPLAY INVISIBLE (-1700 5150);
FORCEPROP 1 LAST TOLERANCE 5%
J 2
(-1850 5150);
DISPLAY 0.510638 (-1850 5150);
PAINT SKYBLUE (-1850 5150);
DISPLAY INVISIBLE (-1850 5150);
FORCEPROP 1 LAST PART_NUMBER CS00002JB13
J 2
(-1750 5200);
DISPLAY 0.510638 (-1750 5200);
PAINT WHITE (-1750 5200);
DISPLAY INVISIBLE (-1750 5200);
FORCEPROP 2 LAST CDS_LIB pure_quanta
J 0
(-2000 5175);
DISPLAY INVISIBLE (-2000 5175);
FORCEPROP 1 LAST PATH I152
J 2
(-1950 5325);
DISPLAY 0.978723 (-1950 5325);
PAINT WHITE (-1950 5325);
DISPLAY INVISIBLE (-1950 5325);
FORCEPROP 1 LAST LOCATION R734
J 2
(-2050 5175);
DISPLAY 0.702128 (-2050 5175);
PAINT YELLOW (-2050 5175);
FORCEPROP 0 LAST $SEC 1
J 0
(-2050 5225);
DISPLAY 0.680851 (-2050 5225);
PAINT MONO (-2050 5225);
DISPLAY INVISIBLE (-2050 5225);
FORCEPROP 0 LAST CDS_SEC 1
J 0
(-2050 5225);
DISPLAY 1.021277 (-2050 5225);
DISPLAY INVISIBLE (-2050 5225);
FORCEPROP 1 LASTPIN (-1900 5175) $PN 1
J 2
(-1912 5187);
DISPLAY 0.808511 (-1912 5187);
PAINT WHITE (-1912 5187);
DISPLAY INVISIBLE (-1912 5187);
FORCEPROP 1 LASTPIN (-2100 5175) $PN 2
J 2
(-2062 5187);
DISPLAY 0.808511 (-2062 5187);
PAINT WHITE (-2062 5187);
DISPLAY INVISIBLE (-2062 5187);
FORCEADD OFFPAGE..5
(-3100 5175);
FORCEPROP 2 LAST $XR0 28 
J 0
(-3354 5175);
DISPLAY 0.638298 (-3354 5175);
PAINT MONO (-3354 5175);
FORCEPROP 2 LAST CDS_LIB standard
J 0
(-3100 5175);
DISPLAY INVISIBLE (-3100 5175);
FORCEPROP 1 LAST OFFPAGE TRUE
J 0
(-2775 5050);
DISPLAY 0.872340 (-2775 5050);
DISPLAY INVISIBLE (-2775 5050);
FORCEPROP 1 LAST COMMENT_BODY TRUE
J 0
(-3000 5100);
DISPLAY 0.872340 (-3000 5100);
PAINT GREEN (-3000 5100);
DISPLAY INVISIBLE (-3000 5100);
FORCEPROP 2 LAST PATH I153
J 0
(-3050 5250);
DISPLAY 0.680851 (-3050 5250);
DISPLAY INVISIBLE (-3050 5250);
FORCEADD Q_RES..1
R 2
(-2200 3775);
FORCEPROP 1 LAST MATERIAL CHIP
J 2
(-1925 3750);
DISPLAY 0.510638 (-1925 3750);
PAINT SKYBLUE (-1925 3750);
FORCEPROP 1 LAST VALUE 0
J 0
(-2150 3750);
DISPLAY 0.510638 (-2150 3750);
PAINT SKYBLUE (-2150 3750);
FORCEPROP 1 LAST PACK_TYPE 0402LF
J 2
(-1600 3750);
DISPLAY 0.510638 (-1600 3750);
PAINT SKYBLUE (-1600 3750);
DISPLAY INVISIBLE (-1600 3750);
FORCEPROP 1 LAST WATTAGE 1/16W
J 0
(-1900 3750);
DISPLAY 0.510638 (-1900 3750);
PAINT SKYBLUE (-1900 3750);
DISPLAY INVISIBLE (-1900 3750);
FORCEPROP 1 LAST TOLERANCE 5%
J 2
(-2050 3750);
DISPLAY 0.510638 (-2050 3750);
PAINT SKYBLUE (-2050 3750);
DISPLAY INVISIBLE (-2050 3750);
FORCEPROP 1 LAST PART_NUMBER CS00002JB13
J 2
(-1950 3800);
DISPLAY 0.510638 (-1950 3800);
PAINT WHITE (-1950 3800);
DISPLAY INVISIBLE (-1950 3800);
FORCEPROP 2 LAST CDS_LIB pure_quanta
J 0
(-2200 3775);
DISPLAY INVISIBLE (-2200 3775);
FORCEPROP 1 LAST PATH I154
J 2
(-2150 3925);
DISPLAY 0.978723 (-2150 3925);
PAINT WHITE (-2150 3925);
DISPLAY INVISIBLE (-2150 3925);
FORCEPROP 1 LAST LOCATION R733
J 2
(-2250 3775);
DISPLAY 0.702128 (-2250 3775);
PAINT YELLOW (-2250 3775);
FORCEPROP 0 LAST $SEC 1
J 0
(-2250 3825);
DISPLAY 0.680851 (-2250 3825);
PAINT MONO (-2250 3825);
DISPLAY INVISIBLE (-2250 3825);
FORCEPROP 0 LAST CDS_SEC 1
J 0
(-2250 3825);
DISPLAY 1.021277 (-2250 3825);
DISPLAY INVISIBLE (-2250 3825);
FORCEPROP 1 LASTPIN (-2100 3775) $PN 1
J 2
(-2112 3787);
DISPLAY 0.808511 (-2112 3787);
PAINT WHITE (-2112 3787);
DISPLAY INVISIBLE (-2112 3787);
FORCEPROP 1 LASTPIN (-2300 3775) $PN 2
J 2
(-2262 3787);
DISPLAY 0.808511 (-2262 3787);
PAINT WHITE (-2262 3787);
DISPLAY INVISIBLE (-2262 3787);
FORCEADD OFFPAGE..5
(-3250 3775);
FORCEPROP 2 LAST $XR0 28 
J 0
(-3474 3775);
DISPLAY 0.638298 (-3474 3775);
PAINT MONO (-3474 3775);
FORCEPROP 2 LAST PATH I155
J 0
(-3200 3850);
DISPLAY 0.680851 (-3200 3850);
DISPLAY INVISIBLE (-3200 3850);
FORCEPROP 1 LAST COMMENT_BODY TRUE
J 0
(-3150 3700);
DISPLAY 0.872340 (-3150 3700);
PAINT GREEN (-3150 3700);
DISPLAY INVISIBLE (-3150 3700);
FORCEPROP 1 LAST OFFPAGE TRUE
J 0
(-2925 3650);
DISPLAY 0.872340 (-2925 3650);
DISPLAY INVISIBLE (-2925 3650);
FORCEPROP 2 LAST CDS_LIB standard
J 0
(-3250 3775);
DISPLAY INVISIBLE (-3250 3775);
FORCEADD BAS70057F..1
R 7
(3975 4950);
FORCEPROP 2 LAST PART_TYPE SMLF
J 2
(3975 5175);
DISPLAY 0.680851 (3975 5175);
FORCEPROP 1 LAST PART_NUMBER BC0BAS70Z01
J 2
(4375 5175);
DISPLAY 0.723404 (4375 5175);
PAINT GREEN (4375 5175);
FORCEPROP 2 LAST VALUE BAS70-05-7-F
J 2
(4375 5075);
DISPLAY 0.680851 (4375 5075);
FORCEPROP 1 LAST MATERIAL IC
J 2
(4075 5125);
DISPLAY 0.723404 (4075 5125);
PAINT GREEN (4075 5125);
FORCEPROP 2 LAST SEC_TYPE 
J 0
(4375 5225);
DISPLAY 0.680851 (4375 5225);
DISPLAY INVISIBLE (4375 5225);
FORCEPROP 1 LAST CDS_LMAN_SYM_OUTLINE -75,50,75,-25
R 1
J 0
(3997 4928);
DISPLAY 0.468085 (3997 4928);
PAINT GREEN (3997 4928);
DISPLAY INVISIBLE (3997 4928);
FORCEPROP 1 LAST NEEDS_NO_SIZE TRUE
R 1
J 0
(3997 4928);
DISPLAY 0.468085 (3997 4928);
PAINT GREEN (3997 4928);
DISPLAY INVISIBLE (3997 4928);
FORCEPROP 2 LAST CDS_LIB pure_quanta
R 1
J 0
(4022 4903);
DISPLAY INVISIBLE (4022 4903);
FORCEPROP 1 LAST PATH I161
R 2
J 2
(3864 4791);
DISPLAY 0.723404 (3864 4791);
PAINT GREEN (3864 4791);
DISPLAY INVISIBLE (3864 4791);
FORCEPROP 1 LAST LOCATION U48
J 2
(3900 5075);
DISPLAY 0.723404 (3900 5075);
PAINT GREEN (3900 5075);
FORCEPROP 0 LASTPIN (3875 5000) $PN 2
J 2
(3865 5010);
DISPLAY 0.680851 (3865 5010);
PAINT MONO (3865 5010);
FORCEPROP 0 LASTPIN (3875 4900) $PN 1
J 2
(3865 4910);
DISPLAY 0.680851 (3865 4910);
PAINT MONO (3865 4910);
FORCEPROP 0 LASTPIN (4075 4950) $PN 3
J 0
(4085 4960);
DISPLAY 0.680851 (4085 4960);
PAINT MONO (4085 4960);
FORCEPROP 2 LAST SEC 1
J 0
(4375 5225);
DISPLAY 0.680851 (4375 5225);
PAINT MONO (4375 5225);
DISPLAY INVISIBLE (4375 5225);
FORCEADD OFFPAGE..1
(3225 4900);
FORCEPROP 2 LAST $XR1 15 
J 0
(2914 4900);
DISPLAY 0.638298 (2914 4900);
PAINT MONO (2914 4900);
FORCEPROP 2 LAST $XR0 10 
J 0
(3004 4900);
DISPLAY 0.638298 (3004 4900);
PAINT MONO (3004 4900);
FORCEPROP 1 LAST COMMENT_BODY TRUE
J 0
(3350 4800);
DISPLAY 0.872340 (3350 4800);
PAINT PEACH (3350 4800);
DISPLAY INVISIBLE (3350 4800);
FORCEPROP 1 LAST OFFPAGE TRUE
J 0
(3550 4775);
DISPLAY 0.872340 (3550 4775);
PAINT GREEN (3550 4775);
DISPLAY INVISIBLE (3550 4775);
FORCEPROP 2 LAST PATH I162
J 0
(2975 4950);
DISPLAY 0.680851 (2975 4950);
DISPLAY INVISIBLE (2975 4950);
FORCEPROP 2 LAST CDS_LIB standard
J 0
(3225 4900);
DISPLAY INVISIBLE (3225 4900);
FORCEADD VCCAUX15..1
(3300 5300);
FORCEPROP 3 LASTPIN (3300 5250) SIG_NAME P3V3_AUX\g
J 0
(3310 5260);
DISPLAY 0.659574 (3310 5260);
PAINT MONO (3310 5260);
DISPLAY INVISIBLE (3310 5260);
FORCEPROP 1 LAST HDL_POWER P3V3_AUX
J 1
(3300 5350);
DISPLAY 0.702128 (3300 5350);
PAINT GREEN (3300 5350);
FORCEPROP 2 LAST CDS_LIB logical_power
J 0
(3300 5300);
DISPLAY INVISIBLE (3300 5300);
FORCEPROP 1 LAST PATH I163
J 0
(3350 5325);
DISPLAY 0.872340 (3350 5325);
PAINT AQUA (3350 5325);
DISPLAY INVISIBLE (3350 5325);
FORCEADD UNIVERSAL_POWER..1
(4650 5275);
FORCEPROP 3 LASTPIN (4650 5225) SIG_NAME P3V3_RTC_AUX\g
J 0
(4660 5235);
DISPLAY 0.659574 (4660 5235);
PAINT MONO (4660 5235);
DISPLAY INVISIBLE (4660 5235);
FORCEPROP 1 LAST HDL_POWER P3V3_RTC_AUX
J 1
(4650 5325);
DISPLAY 0.702128 (4650 5325);
PAINT GREEN (4650 5325);
FORCEPROP 2 LAST CDS_LIB logical_power
J 0
(4650 5275);
DISPLAY INVISIBLE (4650 5275);
FORCEPROP 1 LAST PATH I164
J 0
(4700 5300);
DISPLAY 0.872340 (4700 5300);
PAINT AQUA (4700 5300);
DISPLAY INVISIBLE (4700 5300);
FORCEADD Q_CAP..1
(4650 4700);
FORCEPROP 1 LAST PART_NUMBER CH5104KEB02
J 0
(4700 4550);
DISPLAY 0.978723 (4700 4550);
FORCEPROP 1 LAST MATERIAL X6S
J 0
(4700 4600);
DISPLAY 0.978723 (4700 4600);
FORCEPROP 1 LAST TOLERANCE 10%
J 0
(4700 4650);
DISPLAY 0.978723 (4700 4650);
FORCEPROP 1 LAST VOLTAGE 25V
J 0
(4700 4700);
DISPLAY 0.978723 (4700 4700);
FORCEPROP 1 LAST VALUE 1UF
J 0
(4700 4750);
DISPLAY 0.978723 (4700 4750);
FORCEPROP 1 LAST PACK_TYPE C0402
J 0
(4700 4500);
DISPLAY 0.978723 (4700 4500);
FORCEPROP 2 LAST CDS_LIB pure_quanta
J 0
(4650 4700);
DISPLAY INVISIBLE (4650 4700);
FORCEPROP 1 LAST PATH I165
J 0
(4700 4850);
DISPLAY 0.978723 (4700 4850);
PAINT WHITE (4700 4850);
DISPLAY INVISIBLE (4700 4850);
FORCEPROP 1 LAST LOCATION C196
J 0
(4700 4800);
DISPLAY 0.978723 (4700 4800);
FORCEPROP 1 LASTPIN (4650 4800) $PN 1
J 0
(4660 4780);
DISPLAY 0.787234 (4660 4780);
PAINT MONO (4660 4780);
FORCEPROP 1 LASTPIN (4650 4600) $PN 2
J 0
(4660 4580);
DISPLAY 0.787234 (4660 4580);
PAINT MONO (4660 4580);
FORCEPROP 0 LAST $SEC 1
J 0
(4700 4850);
DISPLAY 0.680851 (4700 4850);
PAINT MONO (4700 4850);
DISPLAY INVISIBLE (4700 4850);
FORCEPROP 0 LAST CDS_SEC 1
J 0
(4700 4850);
DISPLAY 0.680851 (4700 4850);
DISPLAY INVISIBLE (4700 4850);
FORCEADD UNIVERSAL_GND..1
(4650 4375);
FORCEPROP 3 LASTPIN (4650 4425) SIG_NAME GND\g
J 0
(4660 4435);
DISPLAY 0.659574 (4660 4435);
PAINT MONO (4660 4435);
DISPLAY INVISIBLE (4660 4435);
FORCEPROP 1 LAST PATH I166
J 0
(4725 4375);
DISPLAY 0.872340 (4725 4375);
PAINT AQUA (4725 4375);
DISPLAY INVISIBLE (4725 4375);
FORCEPROP 1 LAST HDL_POWER GND
J 1
(4675 4300);
DISPLAY 0.702128 (4675 4300);
PAINT GREEN (4675 4300);
DISPLAY INVISIBLE (4675 4300);
FORCEPROP 2 LAST CDS_LIB logical_power
J 0
(4650 4375);
DISPLAY INVISIBLE (4650 4375);
FORCEADD UNIVERSAL_GND..1
(-3025 4325);
FORCEPROP 3 LASTPIN (-3025 4375) SIG_NAME GND\g
J 0
(-3015 4385);
DISPLAY 0.659574 (-3015 4385);
PAINT MONO (-3015 4385);
DISPLAY INVISIBLE (-3015 4385);
FORCEPROP 1 LAST HDL_POWER GND
J 1
(-3000 4250);
DISPLAY 0.702128 (-3000 4250);
PAINT GREEN (-3000 4250);
DISPLAY INVISIBLE (-3000 4250);
FORCEPROP 2 LAST CDS_LIB logical_power
J 0
(-3025 4325);
DISPLAY INVISIBLE (-3025 4325);
FORCEPROP 1 LAST PATH I169
J 0
(-2950 4325);
DISPLAY 0.872340 (-2950 4325);
PAINT AQUA (-2950 4325);
DISPLAY INVISIBLE (-2950 4325);
FORCEADD UNIVERSAL_GND..1
(-1400 2650);
FORCEPROP 3 LASTPIN (-1400 2700) SIG_NAME GND\g
J 0
(-1390 2710);
DISPLAY 0.659574 (-1390 2710);
PAINT MONO (-1390 2710);
DISPLAY INVISIBLE (-1390 2710);
FORCEPROP 1 LAST HDL_POWER GND
J 1
(-1375 2575);
DISPLAY 0.702128 (-1375 2575);
PAINT GREEN (-1375 2575);
DISPLAY INVISIBLE (-1375 2575);
FORCEPROP 1 LAST PATH I192
J 0
(-1325 2650);
DISPLAY 0.872340 (-1325 2650);
PAINT AQUA (-1325 2650);
DISPLAY INVISIBLE (-1325 2650);
FORCEPROP 2 LAST CDS_LIB logical_power
J 0
(-1400 2650);
DISPLAY INVISIBLE (-1400 2650);
FORCEADD SW_PUSHBUTTON4P_12_G34_H2..1
(-2850 3350);
FORCEPROP 1 LAST PART_NUMBER DHPDTSAM601
J 0
(-2924 3510);
DISPLAY 0.723404 (-2924 3510);
PAINT GREEN (-2924 3510);
FORCEPROP 1 LAST MATERIAL MECH
J 0
(-2924 3460);
DISPLAY 0.723404 (-2924 3460);
PAINT GREEN (-2924 3460);
FORCEPROP 2 LAST PART_TYPE SMLF
J 0
(-2900 3650);
DISPLAY 0.680851 (-2900 3650);
FORCEPROP 2 LAST VALUE SW4S_DTSAM-63N/K-S-Q-T/R
J 0
(-2900 3600);
DISPLAY 0.680851 (-2900 3600);
FORCEPROP 1 LAST NEEDS_NO_SIZE TRUE
J 0
(-2775 3250);
DISPLAY 0.468085 (-2775 3250);
PAINT GREEN (-2775 3250);
DISPLAY INVISIBLE (-2775 3250);
FORCEPROP 1 LAST PATH I204
J 0
(-2850 3350);
DISPLAY 0.723404 (-2850 3350);
PAINT GREEN (-2850 3350);
DISPLAY INVISIBLE (-2850 3350);
FORCEPROP 1 LAST CDS_LMAN_SYM_OUTLINE -75,100,75,-100
J 0
(-2850 3350);
DISPLAY 0.468085 (-2850 3350);
PAINT GREEN (-2850 3350);
DISPLAY INVISIBLE (-2850 3350);
FORCEPROP 2 LAST CDS_LIB pure_quanta
J 0
(-2850 3350);
DISPLAY INVISIBLE (-2850 3350);
FORCEPROP 1 LAST LOCATION SW7
J 0
(-2924 3555);
DISPLAY 0.723404 (-2924 3555);
PAINT GREEN (-2924 3555);
FORCEPROP 0 LASTPIN (-3075 3350) $PN 1
J 2
(-3085 3360);
DISPLAY 0.680851 (-3085 3360);
PAINT MONO (-3085 3360);
FORCEPROP 0 LASTPIN (-2625 3350) $PN 2
J 0
(-2615 3360);
DISPLAY 0.680851 (-2615 3360);
PAINT MONO (-2615 3360);
FORCEPROP 0 LASTPIN (-3075 3300) $PN 3
J 2
(-3085 3310);
DISPLAY 0.680851 (-3085 3310);
PAINT MONO (-3085 3310);
FORCEPROP 0 LASTPIN (-2625 3300) $PN 4
J 0
(-2615 3310);
DISPLAY 0.680851 (-2615 3310);
PAINT MONO (-2615 3310);
FORCEPROP 0 LAST $SEC 1
J 0
(-2900 3700);
DISPLAY 0.680851 (-2900 3700);
PAINT MONO (-2900 3700);
DISPLAY INVISIBLE (-2900 3700);
FORCEPROP 0 LAST CDS_SEC 1
J 0
(-2900 3700);
DISPLAY 0.680851 (-2900 3700);
DISPLAY INVISIBLE (-2900 3700);
FORCEADD UNIVERSAL_GND..1
(750 -525);
FORCEPROP 3 LASTPIN (750 -475) SIG_NAME GND\g
J 0
(760 -465);
DISPLAY 0.659574 (760 -465);
PAINT MONO (760 -465);
DISPLAY INVISIBLE (760 -465);
FORCEPROP 1 LAST HDL_POWER GND
J 1
(775 -600);
DISPLAY 0.702128 (775 -600);
PAINT GREEN (775 -600);
DISPLAY INVISIBLE (775 -600);
FORCEPROP 1 LAST PATH I208
J 0
(825 -525);
DISPLAY 0.872340 (825 -525);
PAINT AQUA (825 -525);
DISPLAY INVISIBLE (825 -525);
FORCEPROP 2 LAST CDS_LIB logical_power
J 0
(750 -525);
DISPLAY INVISIBLE (750 -525);
FORCEADD Q_RES..1
R 1
(750 800);
FORCEPROP 1 LAST WATTAGE 1/16W
R 1
J 2
(825 1100);
DISPLAY 0.723404 (825 1100);
PAINT SKYBLUE (825 1100);
FORCEPROP 1 LAST PACK_TYPE 0402LF
R 1
J 0
(825 700);
DISPLAY 0.723404 (825 700);
PAINT SKYBLUE (825 700);
FORCEPROP 1 LAST MATERIAL CHIP
R 1
J 0
(925 475);
DISPLAY 0.723404 (925 475);
PAINT SKYBLUE (925 475);
FORCEPROP 1 LAST PART_NUMBER CS12202FB04
R 1
J 0
(875 475);
DISPLAY 0.723404 (875 475);
PAINT WHITE (875 475);
FORCEPROP 1 LAST VALUE 220
R 1
J 2
(825 575);
DISPLAY 0.723404 (825 575);
PAINT SKYBLUE (825 575);
FORCEPROP 1 LAST TOLERANCE 1%
R 1
J 0
(825 600);
DISPLAY 0.723404 (825 600);
PAINT SKYBLUE (825 600);
FORCEPROP 2 LAST CDS_LIB pure_quanta
J 0
(750 800);
DISPLAY INVISIBLE (750 800);
FORCEPROP 1 LAST PATH I210
R 1
J 0
(600 750);
DISPLAY 0.978723 (600 750);
PAINT WHITE (600 750);
DISPLAY INVISIBLE (600 750);
FORCEPROP 1 LAST $LOCATION R80
R 1
J 0
(725 525);
DISPLAY 0.723404 (725 525);
PAINT AQUA (725 525);
FORCEPROP 1 LASTPIN (750 700) $PN 1
R 1
J 0
(738 712);
DISPLAY 0.787234 (738 712);
PAINT MONO (738 712);
FORCEPROP 1 LASTPIN (750 900) $PN 2
R 1
J 0
(738 862);
DISPLAY 0.787234 (738 862);
PAINT MONO (738 862);
FORCEPROP 0 LAST CDS_LOCATION R80
R 1
J 0
(775 925);
DISPLAY 0.680851 (775 925);
DISPLAY INVISIBLE (775 925);
FORCEPROP 0 LAST $SEC 1
R 1
J 0
(775 925);
DISPLAY 0.680851 (775 925);
PAINT MONO (775 925);
DISPLAY INVISIBLE (775 925);
FORCEPROP 0 LAST CDS_SEC 1
R 1
J 0
(775 925);
DISPLAY 0.680851 (775 925);
DISPLAY INVISIBLE (775 925);
FORCEADD UNIVERSAL_POWER..1
(750 1175);
FORCEPROP 3 LASTPIN (750 1125) SIG_NAME P5V_AUX\g
J 0
(760 1135);
DISPLAY 0.659574 (760 1135);
PAINT MONO (760 1135);
DISPLAY INVISIBLE (760 1135);
FORCEPROP 1 LAST HDL_POWER P5V_AUX
J 1
(750 1225);
DISPLAY 0.702128 (750 1225);
PAINT RED (750 1225);
FORCEPROP 2 LAST CDS_LIB logical_power
J 0
(750 1175);
DISPLAY INVISIBLE (750 1175);
FORCEPROP 1 LAST PATH I211
J 0
(800 1200);
DISPLAY 0.872340 (800 1200);
PAINT AQUA (800 1200);
DISPLAY INVISIBLE (800 1200);
FORCEADD Q_CAP..1
(750 -200);
FORCEPROP 1 LAST PART_NUMBER CH4104K1B00
J 0
(800 -425);
DISPLAY 0.510638 (800 -425);
PAINT WHITE (800 -425);
FORCEPROP 1 LAST MATERIAL X7R
J 0
(800 -325);
DISPLAY 0.510638 (800 -325);
PAINT SKYBLUE (800 -325);
FORCEPROP 1 LAST TOLERANCE 10%
J 0
(800 -275);
DISPLAY 0.510638 (800 -275);
PAINT SKYBLUE (800 -275);
FORCEPROP 1 LAST PACK_TYPE 0402
J 0
(800 -375);
DISPLAY 0.510638 (800 -375);
PAINT SKYBLUE (800 -375);
FORCEPROP 1 LAST VALUE 0.1UF
J 0
(800 -175);
DISPLAY 0.510638 (800 -175);
PAINT SKYBLUE (800 -175);
FORCEPROP 1 LAST VOLTAGE 25V
J 0
(800 -225);
DISPLAY 0.510638 (800 -225);
PAINT SKYBLUE (800 -225);
FORCEPROP 2 LAST CDS_LIB pure_quanta
J 0
(750 -200);
DISPLAY INVISIBLE (750 -200);
FORCEPROP 1 LAST PATH I212
J 0
(800 -50);
DISPLAY 0.978723 (800 -50);
PAINT WHITE (800 -50);
DISPLAY INVISIBLE (800 -50);
FORCEPROP 1 LAST $LOCATION C27
J 0
(800 -125);
DISPLAY 0.702128 (800 -125);
PAINT YELLOW (800 -125);
FORCEPROP 1 LASTPIN (750 -100) $PN 1
J 0
(760 -120);
DISPLAY 0.808511 (760 -120);
PAINT WHITE (760 -120);
FORCEPROP 1 LASTPIN (750 -300) $PN 2
J 0
(760 -320);
DISPLAY 0.808511 (760 -320);
PAINT WHITE (760 -320);
FORCEPROP 0 LAST CDS_LOCATION C27
J 0
(800 -75);
DISPLAY 0.680851 (800 -75);
DISPLAY INVISIBLE (800 -75);
FORCEPROP 2 LAST $SEC 1
J 0
(800 0);
DISPLAY 0.680851 (800 0);
PAINT MONO (800 0);
DISPLAY INVISIBLE (800 0);
FORCEPROP 0 LAST CDS_SEC 1
J 0
(800 0);
DISPLAY 0.680851 (800 0);
PAINT MONO (800 0);
DISPLAY INVISIBLE (800 0);
FORCEADD UNIVERSAL_GND..1
(-1575 -625);
FORCEPROP 3 LASTPIN (-1575 -575) SIG_NAME GND\g
J 0
(-1565 -565);
DISPLAY 0.659574 (-1565 -565);
PAINT MONO (-1565 -565);
DISPLAY INVISIBLE (-1565 -565);
FORCEPROP 2 LAST CDS_LIB logical_power
J 0
(-1575 -625);
DISPLAY INVISIBLE (-1575 -625);
FORCEPROP 1 LAST PATH I217
J 0
(-1500 -625);
DISPLAY 0.872340 (-1500 -625);
PAINT AQUA (-1500 -625);
DISPLAY INVISIBLE (-1500 -625);
FORCEPROP 1 LAST HDL_POWER GND
J 1
(-1550 -700);
DISPLAY 0.702128 (-1550 -700);
PAINT GREEN (-1550 -700);
DISPLAY INVISIBLE (-1550 -700);
FORCEADD MOSFET_NCH_DUAL..1
(-1625 -275);
FORCEPROP 2 LAST VALUE PJT138K
J 0
(-1450 -250);
DISPLAY 0.680851 (-1450 -250);
FORCEPROP 2 LAST PART_TYPE SMLF
J 0
(-1450 -200);
DISPLAY 0.680851 (-1450 -200);
FORCEPROP 1 LAST PART_NUMBER BAM138K0003
J 0
(-1474 -361);
DISPLAY 0.723404 (-1474 -361);
PAINT GREEN (-1474 -361);
FORCEPROP 1 LAST MATERIAL IC
J 0
(-1474 -426);
DISPLAY 0.723404 (-1474 -426);
PAINT GREEN (-1474 -426);
FORCEPROP 1 LAST PATH I218
J 0
(-1625 -275);
DISPLAY 0.723404 (-1625 -275);
PAINT GREEN (-1625 -275);
DISPLAY INVISIBLE (-1625 -275);
FORCEPROP 1 LAST CDS_LMAN_SYM_OUTLINE -150,150,150,-150
J 0
(-1625 -275);
DISPLAY 0.468085 (-1625 -275);
PAINT GREEN (-1625 -275);
DISPLAY INVISIBLE (-1625 -275);
FORCEPROP 1 LAST NEEDS_NO_SIZE TRUE
J 0
(-1625 -276);
DISPLAY 0.468085 (-1625 -276);
PAINT GREEN (-1625 -276);
DISPLAY INVISIBLE (-1625 -276);
FORCEPROP 2 LAST CDS_LIB pure_quanta
J 0
(-1625 -275);
DISPLAY INVISIBLE (-1625 -275);
FORCEPROP 1 LAST $LOCATION Q13
J 0
(-1474 -301);
DISPLAY 0.723404 (-1474 -301);
PAINT GREEN (-1474 -301);
FORCEPROP 0 LASTPIN (-1575 -75) $PN 6
R 1
J 0
(-1585 -65);
DISPLAY 0.680851 (-1585 -65);
PAINT MONO (-1585 -65);
FORCEPROP 0 LASTPIN (-1825 -325) $PN 2
J 2
(-1835 -315);
DISPLAY 0.680851 (-1835 -315);
PAINT MONO (-1835 -315);
FORCEPROP 0 LASTPIN (-1575 -475) $PN 1
R 1
J 2
(-1585 -485);
DISPLAY 0.680851 (-1585 -485);
PAINT MONO (-1585 -485);
FORCEPROP 0 LAST CDS_LOCATION Q13
J 0
(-1450 -150);
DISPLAY 0.680851 (-1450 -150);
DISPLAY INVISIBLE (-1450 -150);
FORCEPROP 0 LAST $SEC 1
J 0
(-1450 -150);
DISPLAY 0.680851 (-1450 -150);
PAINT MONO (-1450 -150);
DISPLAY INVISIBLE (-1450 -150);
FORCEPROP 0 LAST CDS_SEC 1
J 0
(-1450 -150);
DISPLAY 0.680851 (-1450 -150);
DISPLAY INVISIBLE (-1450 -150);
FORCEADD OFFPAGE..1
(-2800 -325);
FORCEPROP 2 LAST $XR0 22 
J 0
(-3021 -325);
DISPLAY 0.638298 (-3021 -325);
PAINT MONO (-3021 -325);
FORCEPROP 2 LAST CDS_LIB standard
J 0
(-2800 -325);
DISPLAY INVISIBLE (-2800 -325);
FORCEPROP 1 LAST OFFPAGE TRUE
J 0
(-2475 -450);
DISPLAY 0.872340 (-2475 -450);
PAINT GREEN (-2475 -450);
DISPLAY INVISIBLE (-2475 -450);
FORCEPROP 1 LAST COMMENT_BODY TRUE
J 0
(-2675 -425);
DISPLAY 0.872340 (-2675 -425);
PAINT PEACH (-2675 -425);
DISPLAY INVISIBLE (-2675 -425);
FORCEPROP 2 LAST PATH I219
J 0
(-3000 -275);
DISPLAY 0.680851 (-3000 -275);
DISPLAY INVISIBLE (-3000 -275);
FORCEADD UNIVERSAL_POWER..1
(950 2200);
FORCEPROP 3 LASTPIN (950 2150) SIG_NAME P12V_AUX\g
J 0
(960 2160);
DISPLAY 0.659574 (960 2160);
PAINT MONO (960 2160);
DISPLAY INVISIBLE (960 2160);
FORCEPROP 1 LAST HDL_POWER P12V_AUX
J 1
(950 2250);
DISPLAY 0.702128 (950 2250);
PAINT RED (950 2250);
FORCEPROP 2 LAST CDS_LIB logical_power
J 0
(950 2200);
DISPLAY INVISIBLE (950 2200);
FORCEPROP 1 LAST PATH I220
J 0
(1000 2225);
DISPLAY 0.872340 (1000 2225);
PAINT AQUA (1000 2225);
DISPLAY INVISIBLE (1000 2225);
FORCEADD Q_RES..1
(-750 1625);
FORCEPROP 1 LAST WATTAGE 1/16W
J 2
(-775 1475);
DISPLAY 0.638298 (-775 1475);
FORCEPROP 1 LAST PACK_TYPE 0402LF
J 0
(-600 1475);
DISPLAY 0.638298 (-600 1475);
FORCEPROP 1 LAST PART_NUMBER CS13162FB01
J 0
(-800 1725);
DISPLAY 0.638298 (-800 1725);
FORCEPROP 1 LAST VALUE 316
J 2
(-775 1525);
DISPLAY 0.638298 (-775 1525);
FORCEPROP 1 LAST TOLERANCE 1%
J 0
(-750 1525);
DISPLAY 0.638298 (-750 1525);
FORCEPROP 1 LAST MATERIAL CHIP
J 0
(-750 1475);
DISPLAY 0.638298 (-750 1475);
FORCEPROP 1 LAST PATH I222
J 0
(-800 1775);
DISPLAY 0.978723 (-800 1775);
PAINT WHITE (-800 1775);
DISPLAY INVISIBLE (-800 1775);
FORCEPROP 2 LAST CDS_LIB pure_quanta
J 0
(-750 1625);
DISPLAY INVISIBLE (-750 1625);
FORCEPROP 1 LAST $LOCATION R107
J 0
(-800 1675);
DISPLAY 0.808511 (-800 1675);
FORCEPROP 1 LASTPIN (-850 1625) $PN 1
J 0
(-838 1637);
DISPLAY 0.787234 (-838 1637);
PAINT MONO (-838 1637);
FORCEPROP 1 LASTPIN (-650 1625) $PN 2
J 0
(-688 1637);
DISPLAY 0.787234 (-688 1637);
PAINT MONO (-688 1637);
FORCEPROP 0 LAST CDS_LOCATION R107
J 0
(-800 1775);
DISPLAY 0.680851 (-800 1775);
DISPLAY INVISIBLE (-800 1775);
FORCEPROP 0 LAST $SEC 1
J 0
(-800 1775);
DISPLAY 0.680851 (-800 1775);
PAINT MONO (-800 1775);
DISPLAY INVISIBLE (-800 1775);
FORCEPROP 0 LAST CDS_SEC 1
J 0
(-800 1775);
DISPLAY 0.680851 (-800 1775);
DISPLAY INVISIBLE (-800 1775);
FORCEADD Q_RES..1
(-25 1625);
FORCEPROP 1 LAST PACK_TYPE 0402LF
J 0
(125 1475);
DISPLAY 0.638298 (125 1475);
FORCEPROP 1 LAST MATERIAL CHIP
J 0
(-25 1475);
DISPLAY 0.638298 (-25 1475);
FORCEPROP 1 LAST VALUE 316
J 2
(-50 1525);
DISPLAY 0.638298 (-50 1525);
FORCEPROP 1 LAST WATTAGE 1/16W
J 2
(-50 1475);
DISPLAY 0.638298 (-50 1475);
FORCEPROP 1 LAST PART_NUMBER CS13162FB01
J 0
(-75 1725);
DISPLAY 0.638298 (-75 1725);
FORCEPROP 1 LAST TOLERANCE 1%
J 0
(-25 1525);
DISPLAY 0.638298 (-25 1525);
FORCEPROP 2 LAST CDS_LIB pure_quanta
J 0
(-25 1625);
DISPLAY INVISIBLE (-25 1625);
FORCEPROP 1 LAST PATH I224
J 0
(-75 1775);
DISPLAY 0.978723 (-75 1775);
PAINT WHITE (-75 1775);
DISPLAY INVISIBLE (-75 1775);
FORCEPROP 1 LAST $LOCATION R286
J 0
(-75 1675);
DISPLAY 0.978723 (-75 1675);
FORCEPROP 1 LASTPIN (-125 1625) $PN 1
J 0
(-113 1637);
DISPLAY 0.787234 (-113 1637);
PAINT MONO (-113 1637);
FORCEPROP 1 LASTPIN (75 1625) $PN 2
J 0
(37 1637);
DISPLAY 0.787234 (37 1637);
PAINT MONO (37 1637);
FORCEPROP 0 LAST CDS_LOCATION R286
J 0
(-75 1775);
DISPLAY 0.680851 (-75 1775);
DISPLAY INVISIBLE (-75 1775);
FORCEPROP 0 LAST $SEC 1
J 0
(-75 1775);
DISPLAY 0.680851 (-75 1775);
PAINT MONO (-75 1775);
DISPLAY INVISIBLE (-75 1775);
FORCEPROP 0 LAST CDS_SEC 1
J 0
(-75 1775);
DISPLAY 0.680851 (-75 1775);
DISPLAY INVISIBLE (-75 1775);
FORCEADD Q_RES..1
(625 1625);
FORCEPROP 1 LAST PACK_TYPE 0402LF
J 0
(775 1475);
DISPLAY 0.638298 (775 1475);
FORCEPROP 1 LAST MATERIAL CHIP
J 0
(625 1475);
DISPLAY 0.638298 (625 1475);
FORCEPROP 1 LAST WATTAGE 1/16W
J 2
(600 1475);
DISPLAY 0.638298 (600 1475);
FORCEPROP 1 LAST TOLERANCE 1%
J 0
(625 1525);
DISPLAY 0.638298 (625 1525);
FORCEPROP 1 LAST PART_NUMBER CS13162FB01
J 0
(575 1725);
DISPLAY 0.638298 (575 1725);
FORCEPROP 1 LAST VALUE 316
J 2
(600 1525);
DISPLAY 0.638298 (600 1525);
FORCEPROP 2 LAST CDS_LIB pure_quanta
J 0
(625 1625);
DISPLAY INVISIBLE (625 1625);
FORCEPROP 1 LAST PATH I225
J 0
(575 1775);
DISPLAY 0.978723 (575 1775);
PAINT WHITE (575 1775);
DISPLAY INVISIBLE (575 1775);
FORCEPROP 1 LAST $LOCATION R389
J 0
(575 1675);
DISPLAY 0.978723 (575 1675);
FORCEPROP 1 LASTPIN (525 1625) $PN 1
J 0
(537 1637);
DISPLAY 0.787234 (537 1637);
PAINT MONO (537 1637);
FORCEPROP 1 LASTPIN (725 1625) $PN 2
J 0
(687 1637);
DISPLAY 0.787234 (687 1637);
PAINT MONO (687 1637);
FORCEPROP 0 LAST CDS_LOCATION R389
J 0
(575 1775);
DISPLAY 0.680851 (575 1775);
DISPLAY INVISIBLE (575 1775);
FORCEPROP 0 LAST $SEC 1
J 0
(575 1775);
DISPLAY 0.680851 (575 1775);
PAINT MONO (575 1775);
DISPLAY INVISIBLE (575 1775);
FORCEPROP 0 LAST CDS_SEC 1
J 0
(575 1775);
DISPLAY 0.680851 (575 1775);
DISPLAY INVISIBLE (575 1775);
FORCEADD UNIVERSAL_GND..1
(-1825 1450);
FORCEPROP 3 LASTPIN (-1825 1500) SIG_NAME GND\g
J 0
(-1815 1510);
DISPLAY 0.659574 (-1815 1510);
PAINT MONO (-1815 1510);
DISPLAY INVISIBLE (-1815 1510);
FORCEPROP 1 LAST HDL_POWER GND
J 1
(-1800 1375);
DISPLAY 0.702128 (-1800 1375);
PAINT GREEN (-1800 1375);
DISPLAY INVISIBLE (-1800 1375);
FORCEPROP 1 LAST PATH I226
J 0
(-1750 1450);
DISPLAY 0.872340 (-1750 1450);
PAINT AQUA (-1750 1450);
DISPLAY INVISIBLE (-1750 1450);
FORCEPROP 2 LAST CDS_LIB logical_power
J 0
(-1825 1450);
DISPLAY INVISIBLE (-1825 1450);
FORCEADD 74LVC1G07GW..1
(4050 3275);
FORCEPROP 2 LAST VALUE 74LVC1G07GW
J 0
(3875 3600);
DISPLAY 0.510638 (3875 3600);
PAINT SKYBLUE (3875 3600);
FORCEPROP 2 LAST PART_TYPE SMLF
J 0
(3875 3650);
DISPLAY 0.510638 (3875 3650);
PAINT SKYBLUE (3875 3650);
FORCEPROP 1 LAST PART_NUMBER ALVC1G07002
J 0
(3875 3500);
DISPLAY 0.510638 (3875 3500);
PAINT WHITE (3875 3500);
FORCEPROP 1 LAST MATERIAL EMPTY
J 0
(3875 3450);
DISPLAY 0.510638 (3875 3450);
PAINT RED (3875 3450);
FORCEPROP 1 LAST PATH I227
J 0
(4050 3275);
DISPLAY 0.723404 (4050 3275);
PAINT GREEN (4050 3275);
DISPLAY INVISIBLE (4050 3275);
FORCEPROP 2 LAST CDS_LIB pure_quanta
J 0
(4050 3275);
DISPLAY INVISIBLE (4050 3275);
FORCEPROP 1 LAST CDS_LMAN_SYM_OUTLINE -150,150,150,-150
J 0
(4050 3275);
DISPLAY 0.468085 (4050 3275);
PAINT GREEN (4050 3275);
DISPLAY INVISIBLE (4050 3275);
FORCEPROP 2 LAST SEC_TYPE 
J 0
(3875 3675);
DISPLAY 1.021277 (3875 3675);
DISPLAY INVISIBLE (3875 3675);
FORCEPROP 1 LAST $LOCATION U16
J 0
(3875 3550);
DISPLAY 0.702128 (3875 3550);
PAINT YELLOW (3875 3550);
FORCEPROP 0 LASTPIN (3850 3275) $PN 2
J 2
(3840 3285);
DISPLAY 0.680851 (3840 3285);
PAINT MONO (3840 3285);
FORCEPROP 0 LASTPIN (3850 3175) $PN 3
J 2
(3840 3185);
DISPLAY 0.680851 (3840 3185);
PAINT MONO (3840 3185);
FORCEPROP 0 LASTPIN (4250 3175) $PN 1
J 0
(4260 3185);
DISPLAY 0.680851 (4260 3185);
PAINT MONO (4260 3185);
FORCEPROP 0 LASTPIN (3850 3375) $PN 5
J 2
(3840 3385);
DISPLAY 0.680851 (3840 3385);
PAINT MONO (3840 3385);
FORCEPROP 0 LASTPIN (4250 3275) $PN 4
J 0
(4260 3285);
DISPLAY 0.680851 (4260 3285);
PAINT MONO (4260 3285);
FORCEPROP 0 LAST CDS_LOCATION U16
J 0
(3875 3675);
DISPLAY 0.680851 (3875 3675);
DISPLAY INVISIBLE (3875 3675);
FORCEPROP 2 LAST SEC 1
J 0
(3875 3675);
DISPLAY 0.680851 (3875 3675);
PAINT MONO (3875 3675);
DISPLAY INVISIBLE (3875 3675);
FORCEADD OFFPAGE..2
(4950 3275);
FORCEPROP 2 LAST $XR3 34 
J 0
(5409 3275);
DISPLAY 0.638298 (5409 3275);
PAINT MONO (5409 3275);
FORCEPROP 2 LAST $XR2 15 
J 0
(5319 3275);
DISPLAY 0.638298 (5319 3275);
PAINT MONO (5319 3275);
FORCEPROP 2 LAST $XR1 11 
J 0
(5229 3275);
DISPLAY 0.638298 (5229 3275);
PAINT MONO (5229 3275);
FORCEPROP 2 LAST $XR0 10 
J 0
(5139 3275);
DISPLAY 0.638298 (5139 3275);
PAINT MONO (5139 3275);
FORCEPROP 2 LAST PATH I230
J 0
(5425 3325);
DISPLAY 0.680851 (5425 3325);
DISPLAY INVISIBLE (5425 3325);
FORCEPROP 2 LAST CDS_LIB standard
J 0
(4950 3275);
DISPLAY INVISIBLE (4950 3275);
FORCEPROP 1 LAST OFFPAGE TRUE
J 0
(5275 3150);
DISPLAY 0.872340 (5275 3150);
PAINT GREEN (5275 3150);
DISPLAY INVISIBLE (5275 3150);
FORCEPROP 1 LAST COMMENT_BODY TRUE
J 0
(4905 3180);
DISPLAY 0.872340 (4905 3180);
PAINT PEACH (4905 3180);
DISPLAY INVISIBLE (4905 3180);
FORCEADD VCCAUX15..1
(3700 3875);
FORCEPROP 3 LASTPIN (3700 3825) SIG_NAME P3V3_AUX\g
J 0
(3710 3835);
DISPLAY 0.659574 (3710 3835);
PAINT MONO (3710 3835);
DISPLAY INVISIBLE (3710 3835);
FORCEPROP 1 LAST HDL_POWER P3V3_AUX
J 1
(3700 3925);
DISPLAY 0.702128 (3700 3925);
PAINT GREEN (3700 3925);
FORCEPROP 1 LAST PATH I231
J 0
(3750 3900);
DISPLAY 0.872340 (3750 3900);
PAINT AQUA (3750 3900);
DISPLAY INVISIBLE (3750 3900);
FORCEPROP 2 LAST CDS_LIB logical_power
J 0
(3700 3875);
DISPLAY INVISIBLE (3700 3875);
FORCEADD Q_CAP..1
R 2
(3700 3675);
FORCEPROP 1 LAST PACK_TYPE 0402
J 2
(3650 3500);
DISPLAY 0.510638 (3650 3500);
PAINT SKYBLUE (3650 3500);
FORCEPROP 1 LAST PART_NUMBER CH4104K1B00
J 2
(3650 3450);
DISPLAY 0.510638 (3650 3450);
PAINT WHITE (3650 3450);
FORCEPROP 1 LAST VALUE 0.1UF
J 2
(3650 3700);
DISPLAY 0.510638 (3650 3700);
PAINT SKYBLUE (3650 3700);
FORCEPROP 1 LAST VOLTAGE 25V
J 2
(3650 3650);
DISPLAY 0.510638 (3650 3650);
PAINT SKYBLUE (3650 3650);
FORCEPROP 1 LAST TOLERANCE 10%
J 2
(3650 3600);
DISPLAY 0.510638 (3650 3600);
PAINT SKYBLUE (3650 3600);
FORCEPROP 1 LAST MATERIAL EMPTY
J 2
(3650 3550);
DISPLAY 0.510638 (3650 3550);
PAINT RED (3650 3550);
FORCEPROP 1 LAST PATH I232
J 2
(3650 3825);
DISPLAY 0.978723 (3650 3825);
PAINT WHITE (3650 3825);
DISPLAY INVISIBLE (3650 3825);
FORCEPROP 2 LAST CDS_LIB pure_quanta
J 2
(3700 3675);
DISPLAY INVISIBLE (3700 3675);
FORCEPROP 1 LAST $LOCATION C29
J 2
(3650 3750);
DISPLAY 0.702128 (3650 3750);
PAINT YELLOW (3650 3750);
FORCEPROP 1 LASTPIN (3700 3775) $PN 1
J 2
(3690 3755);
DISPLAY 0.808511 (3690 3755);
PAINT WHITE (3690 3755);
FORCEPROP 1 LASTPIN (3700 3575) $PN 2
J 2
(3690 3555);
DISPLAY 0.808511 (3690 3555);
PAINT WHITE (3690 3555);
FORCEPROP 0 LAST CDS_LOCATION C29
J 0
(3650 3800);
DISPLAY 0.680851 (3650 3800);
DISPLAY INVISIBLE (3650 3800);
FORCEPROP 2 LAST $SEC 1
J 2
(3650 3875);
DISPLAY 0.680851 (3650 3875);
PAINT MONO (3650 3875);
DISPLAY INVISIBLE (3650 3875);
FORCEPROP 0 LAST CDS_SEC 1
J 2
(3650 3875);
DISPLAY 0.680851 (3650 3875);
PAINT MONO (3650 3875);
DISPLAY INVISIBLE (3650 3875);
FORCEADD UNIVERSAL_GND..1
(3700 3450);
FORCEPROP 3 LASTPIN (3700 3500) SIG_NAME GND\g
J 0
(3710 3510);
DISPLAY 0.659574 (3710 3510);
PAINT MONO (3710 3510);
DISPLAY INVISIBLE (3710 3510);
FORCEPROP 1 LAST PATH I233
J 0
(3775 3450);
DISPLAY 0.872340 (3775 3450);
PAINT AQUA (3775 3450);
DISPLAY INVISIBLE (3775 3450);
FORCEPROP 2 LAST CDS_LIB logical_power
J 0
(3700 3450);
DISPLAY INVISIBLE (3700 3450);
FORCEPROP 1 LAST HDL_POWER GND
J 1
(3725 3375);
DISPLAY 0.702128 (3725 3375);
PAINT GREEN (3725 3375);
DISPLAY INVISIBLE (3725 3375);
FORCEADD VCCAUX15..1
(3000 3875);
FORCEPROP 3 LASTPIN (3000 3825) SIG_NAME P3V3_AUX\g
J 0
(3010 3835);
DISPLAY 0.659574 (3010 3835);
PAINT MONO (3010 3835);
DISPLAY INVISIBLE (3010 3835);
FORCEPROP 1 LAST HDL_POWER P3V3_AUX
J 1
(3000 3925);
DISPLAY 0.702128 (3000 3925);
PAINT GREEN (3000 3925);
FORCEPROP 1 LAST PATH I234
J 0
(3050 3900);
DISPLAY 0.872340 (3050 3900);
PAINT AQUA (3050 3900);
DISPLAY INVISIBLE (3050 3900);
FORCEPROP 2 LAST CDS_LIB logical_power
J 0
(3000 3875);
DISPLAY INVISIBLE (3000 3875);
FORCEADD Q_RES..2
(3000 3675);
FORCEPROP 1 LAST PACK_TYPE 0402LF
J 0
(3040 3500);
DISPLAY 0.510638 (3040 3500);
PAINT SKYBLUE (3040 3500);
FORCEPROP 1 LAST PART_NUMBER CS28202JB05
J 0
(3040 3550);
DISPLAY 0.510638 (3040 3550);
PAINT WHITE (3040 3550);
FORCEPROP 1 LAST MATERIAL EMPTY
J 0
(3040 3600);
DISPLAY 0.510638 (3040 3600);
PAINT RED (3040 3600);
FORCEPROP 1 LAST WATTAGE 1/16W
J 0
(3040 3650);
DISPLAY 0.510638 (3040 3650);
PAINT SKYBLUE (3040 3650);
FORCEPROP 1 LAST TOLERANCE 5%
J 0
(3045 3700);
DISPLAY 0.510638 (3045 3700);
PAINT SKYBLUE (3045 3700);
FORCEPROP 1 LAST VALUE 8.2K
J 0
(3045 3750);
DISPLAY 0.510638 (3045 3750);
PAINT SKYBLUE (3045 3750);
FORCEPROP 1 LAST PATH I235
J 0
(3050 3850);
DISPLAY 0.978723 (3050 3850);
PAINT WHITE (3050 3850);
DISPLAY INVISIBLE (3050 3850);
FORCEPROP 2 LAST CDS_LIB pure_quanta
J 0
(3000 3675);
DISPLAY INVISIBLE (3000 3675);
FORCEPROP 1 LAST $LOCATION R391
J 0
(3045 3800);
DISPLAY 0.702128 (3045 3800);
PAINT YELLOW (3045 3800);
FORCEPROP 1 LASTPIN (3000 3775) $PN 1
J 0
(3005 3737);
DISPLAY 0.808511 (3005 3737);
PAINT WHITE (3005 3737);
FORCEPROP 1 LASTPIN (3000 3575) $PN 2
J 0
(3005 3585);
DISPLAY 0.808511 (3005 3585);
PAINT WHITE (3005 3585);
FORCEPROP 0 LAST CDS_LOCATION R391
J 0
(3050 3850);
DISPLAY 0.680851 (3050 3850);
DISPLAY INVISIBLE (3050 3850);
FORCEPROP 0 LAST $SEC 1
J 0
(3050 3850);
DISPLAY 0.680851 (3050 3850);
PAINT MONO (3050 3850);
DISPLAY INVISIBLE (3050 3850);
FORCEPROP 0 LAST CDS_SEC 1
J 0
(3050 3850);
DISPLAY 0.680851 (3050 3850);
DISPLAY INVISIBLE (3050 3850);
FORCEADD Q_CAP..1
(3000 3000);
FORCEPROP 1 LAST TOLERANCE 10%
J 0
(3050 2950);
DISPLAY 0.510638 (3050 2950);
PAINT SKYBLUE (3050 2950);
FORCEPROP 1 LAST MATERIAL EMPTY
J 0
(3050 2900);
DISPLAY 0.510638 (3050 2900);
PAINT RED (3050 2900);
FORCEPROP 1 LAST VOLTAGE 25V
J 0
(3050 3000);
DISPLAY 0.510638 (3050 3000);
PAINT SKYBLUE (3050 3000);
FORCEPROP 1 LAST VALUE 1UF
J 0
(3050 3050);
DISPLAY 0.510638 (3050 3050);
PAINT SKYBLUE (3050 3050);
FORCEPROP 1 LAST PACK_TYPE C0402
J 0
(3025 2850);
DISPLAY 0.510638 (3025 2850);
PAINT SKYBLUE (3025 2850);
FORCEPROP 1 LAST PATH I236
J 0
(3050 3150);
DISPLAY 0.978723 (3050 3150);
PAINT WHITE (3050 3150);
DISPLAY INVISIBLE (3050 3150);
FORCEPROP 1 LAST PART_NUMBER CH5104KEB02
J 0
(3050 2850);
DISPLAY 0.510638 (3050 2850);
PAINT WHITE (3050 2850);
DISPLAY INVISIBLE (3050 2850);
FORCEPROP 2 LAST CDS_LIB pure_quanta
J 0
(3000 3000);
DISPLAY INVISIBLE (3000 3000);
FORCEPROP 1 LAST $LOCATION C28
J 0
(3050 3100);
DISPLAY 0.702128 (3050 3100);
PAINT YELLOW (3050 3100);
FORCEPROP 1 LASTPIN (3000 3100) $PN 1
J 0
(3010 3080);
DISPLAY 0.808511 (3010 3080);
PAINT WHITE (3010 3080);
FORCEPROP 1 LASTPIN (3000 2900) $PN 2
J 0
(3010 2880);
DISPLAY 0.808511 (3010 2880);
PAINT WHITE (3010 2880);
FORCEPROP 0 LAST CDS_LOCATION C28
J 0
(3050 3150);
DISPLAY 0.680851 (3050 3150);
DISPLAY INVISIBLE (3050 3150);
FORCEPROP 2 LAST $SEC 1
J 0
(3050 3200);
DISPLAY 0.680851 (3050 3200);
PAINT MONO (3050 3200);
DISPLAY INVISIBLE (3050 3200);
FORCEPROP 0 LAST CDS_SEC 1
J 0
(3050 3200);
DISPLAY 0.680851 (3050 3200);
PAINT MONO (3050 3200);
DISPLAY INVISIBLE (3050 3200);
FORCEADD UNIVERSAL_GND..1
(1600 2125);
FORCEPROP 3 LASTPIN (1600 2175) SIG_NAME GND\g
J 0
(1610 2185);
DISPLAY 0.659574 (1610 2185);
PAINT MONO (1610 2185);
DISPLAY INVISIBLE (1610 2185);
FORCEPROP 1 LAST HDL_POWER GND
J 1
(1625 2050);
DISPLAY 0.702128 (1625 2050);
PAINT GREEN (1625 2050);
DISPLAY INVISIBLE (1625 2050);
FORCEPROP 1 LAST PATH I238
J 0
(1675 2125);
DISPLAY 0.872340 (1675 2125);
PAINT AQUA (1675 2125);
DISPLAY INVISIBLE (1675 2125);
FORCEPROP 2 LAST CDS_LIB logical_power
J 0
(1600 2125);
DISPLAY INVISIBLE (1600 2125);
FORCEADD UNIVERSAL_GND..1
(2875 2650);
FORCEPROP 3 LASTPIN (2875 2700) SIG_NAME GND\g
J 0
(2885 2710);
DISPLAY 0.659574 (2885 2710);
PAINT MONO (2885 2710);
DISPLAY INVISIBLE (2885 2710);
FORCEPROP 1 LAST PATH I239
J 0
(2950 2650);
DISPLAY 0.872340 (2950 2650);
PAINT AQUA (2950 2650);
DISPLAY INVISIBLE (2950 2650);
FORCEPROP 1 LAST HDL_POWER GND
J 1
(2900 2575);
DISPLAY 0.702128 (2900 2575);
PAINT GREEN (2900 2575);
DISPLAY INVISIBLE (2900 2575);
FORCEPROP 2 LAST CDS_LIB logical_power
J 0
(2875 2650);
DISPLAY INVISIBLE (2875 2650);
FORCEADD Q_RES..1
(2675 3275);
FORCEPROP 1 LAST MATERIAL EMPTY
J 0
(2875 3275);
DISPLAY 0.510638 (2875 3275);
PAINT RED (2875 3275);
FORCEPROP 1 LAST VALUE 0
J 2
(2825 3275);
DISPLAY 0.510638 (2825 3275);
PAINT SKYBLUE (2825 3275);
FORCEPROP 1 LAST PATH I241
J 0
(2625 3425);
DISPLAY 0.978723 (2625 3425);
PAINT WHITE (2625 3425);
DISPLAY INVISIBLE (2625 3425);
FORCEPROP 2 LAST CDS_LIB pure_quanta
J 0
(2675 3275);
DISPLAY INVISIBLE (2675 3275);
FORCEPROP 1 LAST PACK_TYPE 0402LF
J 0
(2650 3325);
DISPLAY 0.510638 (2650 3325);
PAINT SKYBLUE (2650 3325);
DISPLAY INVISIBLE (2650 3325);
FORCEPROP 1 LAST WATTAGE 1/16W
J 2
(3025 3375);
DISPLAY 0.510638 (3025 3375);
PAINT SKYBLUE (3025 3375);
DISPLAY INVISIBLE (3025 3375);
FORCEPROP 1 LAST TOLERANCE 5%
J 0
(2600 3375);
DISPLAY 0.510638 (2600 3375);
PAINT SKYBLUE (2600 3375);
DISPLAY INVISIBLE (2600 3375);
FORCEPROP 1 LAST PART_NUMBER CS00002JB13
J 0
(2575 3350);
DISPLAY 0.510638 (2575 3350);
PAINT WHITE (2575 3350);
DISPLAY INVISIBLE (2575 3350);
FORCEPROP 1 LAST $LOCATION R470
J 0
(2450 3275);
DISPLAY 0.702128 (2450 3275);
PAINT YELLOW (2450 3275);
FORCEPROP 1 LASTPIN (2575 3275) $PN 1
J 0
(2587 3287);
DISPLAY 0.787234 (2587 3287);
PAINT MONO (2587 3287);
FORCEPROP 1 LASTPIN (2775 3275) $PN 2
J 0
(2737 3287);
DISPLAY 0.787234 (2737 3287);
PAINT MONO (2737 3287);
FORCEPROP 0 LAST CDS_LOCATION R470
J 0
(2450 3325);
DISPLAY 0.680851 (2450 3325);
DISPLAY INVISIBLE (2450 3325);
FORCEPROP 0 LAST $SEC 1
J 0
(2450 3325);
DISPLAY 0.680851 (2450 3325);
PAINT MONO (2450 3325);
DISPLAY INVISIBLE (2450 3325);
FORCEPROP 0 LAST CDS_SEC 1
J 0
(2450 3325);
DISPLAY 0.680851 (2450 3325);
DISPLAY INVISIBLE (2450 3325);
FORCEADD Q_RES..1
(4100 2550);
FORCEPROP 1 LAST VALUE 0
J 2
(4250 2550);
DISPLAY 0.510638 (4250 2550);
PAINT SKYBLUE (4250 2550);
FORCEPROP 1 LAST MATERIAL CHIP
J 0
(4300 2550);
DISPLAY 0.510638 (4300 2550);
PAINT RED (4300 2550);
FORCEPROP 2 LAST CDS_LIB pure_quanta
J 0
(4100 2550);
DISPLAY INVISIBLE (4100 2550);
FORCEPROP 1 LAST PATH I242
J 0
(4050 2700);
DISPLAY 0.978723 (4050 2700);
PAINT WHITE (4050 2700);
DISPLAY INVISIBLE (4050 2700);
FORCEPROP 1 LAST PART_NUMBER CS00002JB13
J 0
(4000 2625);
DISPLAY 0.510638 (4000 2625);
PAINT WHITE (4000 2625);
DISPLAY INVISIBLE (4000 2625);
FORCEPROP 1 LAST TOLERANCE 5%
J 0
(4025 2650);
DISPLAY 0.510638 (4025 2650);
PAINT SKYBLUE (4025 2650);
DISPLAY INVISIBLE (4025 2650);
FORCEPROP 1 LAST WATTAGE 1/16W
J 2
(4450 2650);
DISPLAY 0.510638 (4450 2650);
PAINT SKYBLUE (4450 2650);
DISPLAY INVISIBLE (4450 2650);
FORCEPROP 1 LAST PACK_TYPE 0402LF
J 0
(4075 2600);
DISPLAY 0.510638 (4075 2600);
PAINT SKYBLUE (4075 2600);
DISPLAY INVISIBLE (4075 2600);
FORCEPROP 1 LAST $LOCATION R471
J 0
(4050 2600);
DISPLAY 0.978723 (4050 2600);
FORCEPROP 1 LASTPIN (4000 2550) $PN 1
J 0
(4012 2562);
DISPLAY 0.787234 (4012 2562);
PAINT MONO (4012 2562);
FORCEPROP 1 LASTPIN (4200 2550) $PN 2
J 0
(4162 2562);
DISPLAY 0.787234 (4162 2562);
PAINT MONO (4162 2562);
FORCEPROP 0 LAST CDS_LOCATION R471
J 0
(4050 2650);
DISPLAY 0.680851 (4050 2650);
DISPLAY INVISIBLE (4050 2650);
FORCEPROP 0 LAST $SEC 1
J 0
(4050 2650);
DISPLAY 0.680851 (4050 2650);
PAINT MONO (4050 2650);
DISPLAY INVISIBLE (4050 2650);
FORCEPROP 0 LAST CDS_SEC 1
J 0
(4050 2650);
DISPLAY 0.680851 (4050 2650);
DISPLAY INVISIBLE (4050 2650);
FORCEADD OFFPAGE..2
(5000 2550);
FORCEPROP 2 LAST $XR2 15 
J 0
(5369 2550);
DISPLAY 0.638298 (5369 2550);
PAINT MONO (5369 2550);
FORCEPROP 2 LAST $XR3 34 
J 0
(5459 2550);
DISPLAY 0.638298 (5459 2550);
PAINT MONO (5459 2550);
FORCEPROP 2 LAST $XR0 10 
J 0
(5189 2550);
DISPLAY 0.638298 (5189 2550);
PAINT MONO (5189 2550);
FORCEPROP 2 LAST $XR1 11 
J 0
(5279 2550);
DISPLAY 0.638298 (5279 2550);
PAINT MONO (5279 2550);
FORCEPROP 1 LAST COMMENT_BODY TRUE
J 0
(4955 2455);
DISPLAY 0.872340 (4955 2455);
PAINT PEACH (4955 2455);
DISPLAY INVISIBLE (4955 2455);
FORCEPROP 1 LAST OFFPAGE TRUE
J 0
(5325 2425);
DISPLAY 0.872340 (5325 2425);
PAINT GREEN (5325 2425);
DISPLAY INVISIBLE (5325 2425);
FORCEPROP 2 LAST CDS_LIB standard
J 0
(5000 2550);
DISPLAY INVISIBLE (5000 2550);
FORCEPROP 2 LAST PATH I243
J 0
(5475 2600);
DISPLAY 0.680851 (5475 2600);
DISPLAY INVISIBLE (5475 2600);
FORCEADD DIODE_BIDIRECTIONAL..1
(4100 2225);
FORCEPROP 1 LAST PART_NUMBER BC00511TZ00
J 0
(3992 2337);
DISPLAY 0.723404 (3992 2337);
PAINT GREEN (3992 2337);
FORCEPROP 1 LAST MATERIAL IC
J 0
(3992 2280);
DISPLAY 0.723404 (3992 2280);
PAINT GREEN (3992 2280);
FORCEPROP 2 LAST VALUE UCLAMP0511T
J 0
(4000 2425);
DISPLAY 0.680851 (4000 2425);
FORCEPROP 2 LAST PART_TYPE SMLF
J 0
(4000 2475);
DISPLAY 0.680851 (4000 2475);
FORCEPROP 1 LAST CDS_LMAN_SYM_OUTLINE -100,50,100,-50
J 0
(4100 2225);
DISPLAY 0.468085 (4100 2225);
PAINT GREEN (4100 2225);
DISPLAY INVISIBLE (4100 2225);
FORCEPROP 1 LAST NEEDS_NO_SIZE TRUE
J 0
(4100 2225);
DISPLAY 0.723404 (4100 2225);
PAINT GREEN (4100 2225);
DISPLAY INVISIBLE (4100 2225);
FORCEPROP 1 LASTPIN (4250 2225) Pin_Length Short
J 0
(4275 2215);
DISPLAY 0.489362 (4275 2215);
PAINT MONO (4275 2215);
DISPLAY INVISIBLE (4275 2215);
FORCEPROP 1 LAST PATH I244
J 0
(4100 2225);
DISPLAY 0.723404 (4100 2225);
PAINT GREEN (4100 2225);
DISPLAY INVISIBLE (4100 2225);
FORCEPROP 2 LAST CDS_LIB pure_quanta
J 0
(4100 2225);
DISPLAY INVISIBLE (4100 2225);
FORCEPROP 1 LAST $LOCATION D10
J 0
(3992 2389);
DISPLAY 0.723404 (3992 2389);
PAINT GREEN (3992 2389);
FORCEPROP 0 LASTPIN (3950 2225) $PN A
J 2
(3940 2235);
DISPLAY 0.680851 (3940 2235);
PAINT MONO (3940 2235);
FORCEPROP 0 LASTPIN (4250 2225) $PN C
J 0
(4260 2235);
DISPLAY 0.680851 (4260 2235);
PAINT MONO (4260 2235);
FORCEPROP 0 LAST CDS_LOCATION D10
J 0
(4000 2525);
DISPLAY 0.680851 (4000 2525);
DISPLAY INVISIBLE (4000 2525);
FORCEPROP 0 LAST $SEC 1
J 0
(4000 2525);
DISPLAY 0.680851 (4000 2525);
PAINT MONO (4000 2525);
DISPLAY INVISIBLE (4000 2525);
FORCEPROP 0 LAST CDS_SEC 1
J 0
(4000 2525);
DISPLAY 0.680851 (4000 2525);
DISPLAY INVISIBLE (4000 2525);
FORCEADD UNIVERSAL_GND..1
(4425 2075);
FORCEPROP 3 LASTPIN (4425 2125) SIG_NAME GND\g
J 0
(4435 2135);
DISPLAY 0.659574 (4435 2135);
PAINT MONO (4435 2135);
DISPLAY INVISIBLE (4435 2135);
FORCEPROP 1 LAST HDL_POWER GND
J 1
(4450 2000);
DISPLAY 0.702128 (4450 2000);
PAINT GREEN (4450 2000);
DISPLAY INVISIBLE (4450 2000);
FORCEPROP 1 LAST PATH I245
J 0
(4500 2075);
DISPLAY 0.872340 (4500 2075);
PAINT AQUA (4500 2075);
DISPLAY INVISIBLE (4500 2075);
FORCEPROP 2 LAST CDS_LIB logical_power
J 0
(4425 2075);
DISPLAY INVISIBLE (4425 2075);
FORCEADD Q_CAP..1
R 2
(3800 2075);
FORCEPROP 1 LAST PART_NUMBER CH4104K1B00
J 2
(3750 1850);
DISPLAY 0.510638 (3750 1850);
PAINT WHITE (3750 1850);
FORCEPROP 1 LAST PACK_TYPE 0402
J 2
(3750 1900);
DISPLAY 0.510638 (3750 1900);
PAINT SKYBLUE (3750 1900);
FORCEPROP 1 LAST VALUE 0.1UF
J 2
(3750 2100);
DISPLAY 0.510638 (3750 2100);
PAINT SKYBLUE (3750 2100);
FORCEPROP 1 LAST VOLTAGE 25V
J 2
(3750 2050);
DISPLAY 0.510638 (3750 2050);
PAINT SKYBLUE (3750 2050);
FORCEPROP 1 LAST TOLERANCE 10%
J 2
(3750 2000);
DISPLAY 0.510638 (3750 2000);
PAINT SKYBLUE (3750 2000);
FORCEPROP 1 LAST MATERIAL X7R
J 2
(3750 1950);
DISPLAY 0.510638 (3750 1950);
PAINT SKYBLUE (3750 1950);
FORCEPROP 1 LAST PATH I246
J 2
(3750 2225);
DISPLAY 0.978723 (3750 2225);
PAINT WHITE (3750 2225);
DISPLAY INVISIBLE (3750 2225);
FORCEPROP 2 LAST CDS_LIB pure_quanta
J 0
(3800 2075);
DISPLAY INVISIBLE (3800 2075);
FORCEPROP 1 LAST $LOCATION C181
J 2
(3750 2150);
DISPLAY 0.702128 (3750 2150);
PAINT YELLOW (3750 2150);
FORCEPROP 1 LASTPIN (3800 2175) $PN 1
J 2
(3790 2155);
DISPLAY 0.787234 (3790 2155);
PAINT MONO (3790 2155);
FORCEPROP 1 LASTPIN (3800 1975) $PN 2
J 2
(3790 1955);
DISPLAY 0.787234 (3790 1955);
PAINT MONO (3790 1955);
FORCEPROP 0 LAST CDS_LOCATION C181
J 0
(3750 2200);
DISPLAY 0.680851 (3750 2200);
DISPLAY INVISIBLE (3750 2200);
FORCEPROP 0 LAST $SEC 1
J 0
(3750 2200);
DISPLAY 0.680851 (3750 2200);
PAINT MONO (3750 2200);
DISPLAY INVISIBLE (3750 2200);
FORCEPROP 0 LAST CDS_SEC 1
J 0
(3750 2200);
DISPLAY 0.680851 (3750 2200);
DISPLAY INVISIBLE (3750 2200);
FORCEADD UNIVERSAL_GND..1
(3800 1825);
FORCEPROP 3 LASTPIN (3800 1875) SIG_NAME GND\g
J 0
(3810 1885);
DISPLAY 0.659574 (3810 1885);
PAINT MONO (3810 1885);
DISPLAY INVISIBLE (3810 1885);
FORCEPROP 1 LAST HDL_POWER GND
J 1
(3825 1750);
DISPLAY 0.702128 (3825 1750);
PAINT GREEN (3825 1750);
DISPLAY INVISIBLE (3825 1750);
FORCEPROP 1 LAST PATH I247
J 0
(3875 1825);
DISPLAY 0.872340 (3875 1825);
PAINT AQUA (3875 1825);
DISPLAY INVISIBLE (3875 1825);
FORCEPROP 2 LAST CDS_LIB logical_power
J 0
(3800 1825);
DISPLAY INVISIBLE (3800 1825);
FORCEADD 74LVC1G07GW..1
(4100 1050);
FORCEPROP 2 LAST VALUE 74LVC1G07GW
J 0
(3925 1375);
DISPLAY 0.510638 (3925 1375);
PAINT SKYBLUE (3925 1375);
FORCEPROP 2 LAST PART_TYPE SMLF
J 0
(3925 1425);
DISPLAY 0.510638 (3925 1425);
PAINT SKYBLUE (3925 1425);
FORCEPROP 1 LAST PART_NUMBER ALVC1G07002
J 0
(3925 1275);
DISPLAY 0.510638 (3925 1275);
PAINT WHITE (3925 1275);
FORCEPROP 1 LAST MATERIAL IC
J 0
(3925 1225);
DISPLAY 0.510638 (3925 1225);
PAINT SKYBLUE (3925 1225);
FORCEPROP 2 LAST CDS_LIB pure_quanta
J 0
(4100 1050);
DISPLAY INVISIBLE (4100 1050);
FORCEPROP 1 LAST CDS_LMAN_SYM_OUTLINE -150,150,150,-150
J 0
(4100 1050);
DISPLAY 0.468085 (4100 1050);
PAINT GREEN (4100 1050);
DISPLAY INVISIBLE (4100 1050);
FORCEPROP 2 LAST SEC_TYPE 
J 0
(3925 1450);
DISPLAY 1.021277 (3925 1450);
DISPLAY INVISIBLE (3925 1450);
FORCEPROP 1 LAST PATH I278
J 0
(4100 1050);
DISPLAY 0.723404 (4100 1050);
PAINT GREEN (4100 1050);
DISPLAY INVISIBLE (4100 1050);
FORCEPROP 1 LAST $LOCATION U57
J 0
(3925 1325);
DISPLAY 0.702128 (3925 1325);
PAINT YELLOW (3925 1325);
FORCEPROP 0 LASTPIN (3900 1050) $PN 2
J 2
(3890 1060);
DISPLAY 0.680851 (3890 1060);
PAINT MONO (3890 1060);
FORCEPROP 0 LASTPIN (3900 950) $PN 3
J 2
(3890 960);
DISPLAY 0.680851 (3890 960);
PAINT MONO (3890 960);
FORCEPROP 0 LASTPIN (4300 950) $PN 1
J 0
(4310 960);
DISPLAY 0.680851 (4310 960);
PAINT MONO (4310 960);
FORCEPROP 0 LASTPIN (3900 1150) $PN 5
J 2
(3890 1160);
DISPLAY 0.680851 (3890 1160);
PAINT MONO (3890 1160);
FORCEPROP 0 LASTPIN (4300 1050) $PN 4
J 0
(4310 1060);
DISPLAY 0.680851 (4310 1060);
PAINT MONO (4310 1060);
FORCEPROP 0 LAST CDS_LOCATION U57
J 0
(3925 1450);
DISPLAY 0.680851 (3925 1450);
DISPLAY INVISIBLE (3925 1450);
FORCEPROP 2 LAST SEC 1
J 0
(3925 1450);
DISPLAY 0.680851 (3925 1450);
PAINT MONO (3925 1450);
DISPLAY INVISIBLE (3925 1450);
FORCEADD OFFPAGE..2
(5000 1050);
FORCEPROP 2 LAST $XR3 34 
J 0
(5459 1050);
DISPLAY 0.638298 (5459 1050);
PAINT MONO (5459 1050);
FORCEPROP 2 LAST $XR2 15 
J 0
(5369 1050);
DISPLAY 0.638298 (5369 1050);
PAINT MONO (5369 1050);
FORCEPROP 2 LAST $XR1 11 
J 0
(5279 1050);
DISPLAY 0.638298 (5279 1050);
PAINT MONO (5279 1050);
FORCEPROP 2 LAST $XR0 10 
J 0
(5189 1050);
DISPLAY 0.638298 (5189 1050);
PAINT MONO (5189 1050);
FORCEPROP 2 LAST PATH I279
J 0
(5475 1100);
DISPLAY 0.680851 (5475 1100);
DISPLAY INVISIBLE (5475 1100);
FORCEPROP 1 LAST COMMENT_BODY TRUE
J 0
(4955 955);
DISPLAY 0.872340 (4955 955);
PAINT PEACH (4955 955);
DISPLAY INVISIBLE (4955 955);
FORCEPROP 1 LAST OFFPAGE TRUE
J 0
(5325 925);
DISPLAY 0.872340 (5325 925);
PAINT GREEN (5325 925);
DISPLAY INVISIBLE (5325 925);
FORCEPROP 2 LAST CDS_LIB standard
J 0
(5000 1050);
DISPLAY INVISIBLE (5000 1050);
FORCEADD VCCAUX15..1
(3750 1650);
FORCEPROP 3 LASTPIN (3750 1600) SIG_NAME P3V3_AUX\g
J 0
(3760 1610);
DISPLAY 0.659574 (3760 1610);
PAINT MONO (3760 1610);
DISPLAY INVISIBLE (3760 1610);
FORCEPROP 1 LAST HDL_POWER P3V3_AUX
J 1
(3750 1700);
DISPLAY 0.702128 (3750 1700);
PAINT GREEN (3750 1700);
FORCEPROP 2 LAST CDS_LIB logical_power
J 0
(3750 1650);
DISPLAY INVISIBLE (3750 1650);
FORCEPROP 1 LAST PATH I280
J 0
(3800 1675);
DISPLAY 0.872340 (3800 1675);
PAINT AQUA (3800 1675);
DISPLAY INVISIBLE (3800 1675);
FORCEADD Q_CAP..1
R 2
(3750 1450);
FORCEPROP 1 LAST PART_NUMBER CH4104K1B00
J 2
(3700 1225);
DISPLAY 0.510638 (3700 1225);
PAINT WHITE (3700 1225);
FORCEPROP 1 LAST TOLERANCE 10%
J 2
(3700 1375);
DISPLAY 0.510638 (3700 1375);
PAINT SKYBLUE (3700 1375);
FORCEPROP 1 LAST VOLTAGE 25V
J 2
(3700 1425);
DISPLAY 0.510638 (3700 1425);
PAINT SKYBLUE (3700 1425);
FORCEPROP 1 LAST PACK_TYPE 0402
J 2
(3700 1275);
DISPLAY 0.510638 (3700 1275);
PAINT SKYBLUE (3700 1275);
FORCEPROP 1 LAST MATERIAL X7R
J 2
(3700 1325);
DISPLAY 0.510638 (3700 1325);
PAINT SKYBLUE (3700 1325);
FORCEPROP 1 LAST VALUE 0.1UF
J 2
(3700 1475);
DISPLAY 0.510638 (3700 1475);
PAINT SKYBLUE (3700 1475);
FORCEPROP 2 LAST CDS_LIB pure_quanta
J 2
(3750 1450);
DISPLAY INVISIBLE (3750 1450);
FORCEPROP 1 LAST PATH I281
J 2
(3700 1600);
DISPLAY 0.978723 (3700 1600);
PAINT WHITE (3700 1600);
DISPLAY INVISIBLE (3700 1600);
FORCEPROP 1 LAST $LOCATION C336
J 2
(3700 1525);
DISPLAY 0.702128 (3700 1525);
PAINT YELLOW (3700 1525);
FORCEPROP 1 LASTPIN (3750 1550) $PN 1
J 2
(3740 1530);
DISPLAY 0.808511 (3740 1530);
PAINT WHITE (3740 1530);
FORCEPROP 1 LASTPIN (3750 1350) $PN 2
J 2
(3740 1330);
DISPLAY 0.808511 (3740 1330);
PAINT WHITE (3740 1330);
FORCEPROP 0 LAST CDS_LOCATION C336
J 0
(3700 1575);
DISPLAY 0.680851 (3700 1575);
DISPLAY INVISIBLE (3700 1575);
FORCEPROP 2 LAST $SEC 1
J 2
(3700 1650);
DISPLAY 0.680851 (3700 1650);
PAINT MONO (3700 1650);
DISPLAY INVISIBLE (3700 1650);
FORCEPROP 0 LAST CDS_SEC 1
J 2
(3700 1650);
DISPLAY 0.680851 (3700 1650);
PAINT MONO (3700 1650);
DISPLAY INVISIBLE (3700 1650);
FORCEADD UNIVERSAL_GND..1
(3750 1225);
FORCEPROP 3 LASTPIN (3750 1275) SIG_NAME GND\g
J 0
(3760 1285);
DISPLAY 0.659574 (3760 1285);
PAINT MONO (3760 1285);
DISPLAY INVISIBLE (3760 1285);
FORCEPROP 1 LAST HDL_POWER GND
J 1
(3775 1150);
DISPLAY 0.702128 (3775 1150);
PAINT GREEN (3775 1150);
DISPLAY INVISIBLE (3775 1150);
FORCEPROP 2 LAST CDS_LIB logical_power
J 0
(3750 1225);
DISPLAY INVISIBLE (3750 1225);
FORCEPROP 1 LAST PATH I282
J 0
(3825 1225);
DISPLAY 0.872340 (3825 1225);
PAINT AQUA (3825 1225);
DISPLAY INVISIBLE (3825 1225);
FORCEADD VCCAUX15..1
(2975 1650);
FORCEPROP 3 LASTPIN (2975 1600) SIG_NAME P3V3_AUX\g
J 0
(2985 1610);
DISPLAY 0.659574 (2985 1610);
PAINT MONO (2985 1610);
DISPLAY INVISIBLE (2985 1610);
FORCEPROP 1 LAST HDL_POWER P3V3_AUX
J 1
(2975 1700);
DISPLAY 0.702128 (2975 1700);
PAINT GREEN (2975 1700);
FORCEPROP 2 LAST CDS_LIB logical_power
J 0
(2975 1650);
DISPLAY INVISIBLE (2975 1650);
FORCEPROP 1 LAST PATH I283
J 0
(3025 1675);
DISPLAY 0.872340 (3025 1675);
PAINT AQUA (3025 1675);
DISPLAY INVISIBLE (3025 1675);
FORCEADD Q_RES..2
(2975 1450);
FORCEPROP 1 LAST MATERIAL EMPTY
J 0
(3015 1375);
DISPLAY 0.510638 (3015 1375);
PAINT RED (3015 1375);
FORCEPROP 1 LAST PART_NUMBER CS28202JB05
J 0
(3015 1325);
DISPLAY 0.510638 (3015 1325);
PAINT WHITE (3015 1325);
FORCEPROP 1 LAST WATTAGE 1/16W
J 0
(3015 1425);
DISPLAY 0.510638 (3015 1425);
PAINT SKYBLUE (3015 1425);
FORCEPROP 1 LAST PACK_TYPE 0402LF
J 0
(3015 1275);
DISPLAY 0.510638 (3015 1275);
PAINT SKYBLUE (3015 1275);
FORCEPROP 1 LAST TOLERANCE 5%
J 0
(3020 1475);
DISPLAY 0.510638 (3020 1475);
PAINT SKYBLUE (3020 1475);
FORCEPROP 1 LAST VALUE 8.2K
J 0
(3020 1525);
DISPLAY 0.510638 (3020 1525);
PAINT SKYBLUE (3020 1525);
FORCEPROP 1 LAST PATH I284
J 0
(3025 1625);
DISPLAY 0.978723 (3025 1625);
PAINT WHITE (3025 1625);
DISPLAY INVISIBLE (3025 1625);
FORCEPROP 2 LAST CDS_LIB pure_quanta
J 0
(2975 1450);
DISPLAY INVISIBLE (2975 1450);
FORCEPROP 1 LAST $LOCATION R883
J 0
(3020 1575);
DISPLAY 0.702128 (3020 1575);
PAINT YELLOW (3020 1575);
FORCEPROP 1 LASTPIN (2975 1550) $PN 1
J 0
(2980 1512);
DISPLAY 0.808511 (2980 1512);
PAINT WHITE (2980 1512);
FORCEPROP 1 LASTPIN (2975 1350) $PN 2
J 0
(2980 1360);
DISPLAY 0.808511 (2980 1360);
PAINT WHITE (2980 1360);
FORCEPROP 0 LAST CDS_LOCATION R883
J 0
(3025 1625);
DISPLAY 0.680851 (3025 1625);
DISPLAY INVISIBLE (3025 1625);
FORCEPROP 0 LAST $SEC 1
J 0
(3025 1625);
DISPLAY 0.680851 (3025 1625);
PAINT MONO (3025 1625);
DISPLAY INVISIBLE (3025 1625);
FORCEPROP 0 LAST CDS_SEC 1
J 0
(3025 1625);
DISPLAY 0.680851 (3025 1625);
DISPLAY INVISIBLE (3025 1625);
FORCEADD Q_CAP..1
(3050 775);
FORCEPROP 1 LAST MATERIAL X6S
J 0
(3100 675);
DISPLAY 0.510638 (3100 675);
PAINT SKYBLUE (3100 675);
FORCEPROP 1 LAST TOLERANCE 10%
J 0
(3100 725);
DISPLAY 0.510638 (3100 725);
PAINT SKYBLUE (3100 725);
FORCEPROP 1 LAST VOLTAGE 25V
J 0
(3100 775);
DISPLAY 0.510638 (3100 775);
PAINT SKYBLUE (3100 775);
FORCEPROP 1 LAST VALUE 1UF
J 0
(3100 825);
DISPLAY 0.510638 (3100 825);
PAINT SKYBLUE (3100 825);
FORCEPROP 1 LAST PACK_TYPE C0402
J 0
(3075 625);
DISPLAY 0.510638 (3075 625);
PAINT SKYBLUE (3075 625);
FORCEPROP 1 LAST PART_NUMBER CH5104KEB02
J 0
(3100 625);
DISPLAY 0.510638 (3100 625);
PAINT WHITE (3100 625);
DISPLAY INVISIBLE (3100 625);
FORCEPROP 2 LAST CDS_LIB pure_quanta
J 0
(3050 775);
DISPLAY INVISIBLE (3050 775);
FORCEPROP 1 LAST PATH I285
J 0
(3100 925);
DISPLAY 0.978723 (3100 925);
PAINT WHITE (3100 925);
DISPLAY INVISIBLE (3100 925);
FORCEPROP 1 LAST $LOCATION C335
J 0
(3100 875);
DISPLAY 0.702128 (3100 875);
PAINT YELLOW (3100 875);
FORCEPROP 1 LASTPIN (3050 875) $PN 1
J 0
(3060 855);
DISPLAY 0.808511 (3060 855);
PAINT WHITE (3060 855);
FORCEPROP 1 LASTPIN (3050 675) $PN 2
J 0
(3060 655);
DISPLAY 0.808511 (3060 655);
PAINT WHITE (3060 655);
FORCEPROP 0 LAST CDS_LOCATION C335
J 0
(3100 925);
DISPLAY 0.680851 (3100 925);
DISPLAY INVISIBLE (3100 925);
FORCEPROP 2 LAST $SEC 1
J 0
(3100 975);
DISPLAY 0.680851 (3100 975);
PAINT MONO (3100 975);
DISPLAY INVISIBLE (3100 975);
FORCEPROP 0 LAST CDS_SEC 1
J 0
(3100 975);
DISPLAY 0.680851 (3100 975);
PAINT MONO (3100 975);
DISPLAY INVISIBLE (3100 975);
FORCEADD Q_RES..1
(2650 1050);
FORCEPROP 1 LAST VALUE 0
J 2
(2800 1050);
DISPLAY 0.510638 (2800 1050);
PAINT SKYBLUE (2800 1050);
FORCEPROP 1 LAST MATERIAL CHIP
J 0
(2850 1050);
DISPLAY 0.510638 (2850 1050);
PAINT SKYBLUE (2850 1050);
FORCEPROP 2 LAST CDS_LIB pure_quanta
J 0
(2650 1050);
DISPLAY INVISIBLE (2650 1050);
FORCEPROP 1 LAST PACK_TYPE 0402LF
J 0
(2625 1100);
DISPLAY 0.510638 (2625 1100);
PAINT SKYBLUE (2625 1100);
DISPLAY INVISIBLE (2625 1100);
FORCEPROP 1 LAST WATTAGE 1/16W
J 2
(3000 1150);
DISPLAY 0.510638 (3000 1150);
PAINT SKYBLUE (3000 1150);
DISPLAY INVISIBLE (3000 1150);
FORCEPROP 1 LAST TOLERANCE 5%
J 0
(2575 1150);
DISPLAY 0.510638 (2575 1150);
PAINT SKYBLUE (2575 1150);
DISPLAY INVISIBLE (2575 1150);
FORCEPROP 1 LAST PART_NUMBER CS00002JB13
J 0
(2550 1125);
DISPLAY 0.510638 (2550 1125);
PAINT WHITE (2550 1125);
DISPLAY INVISIBLE (2550 1125);
FORCEPROP 1 LAST PATH I286
J 0
(2600 1200);
DISPLAY 0.978723 (2600 1200);
PAINT WHITE (2600 1200);
DISPLAY INVISIBLE (2600 1200);
FORCEPROP 1 LAST $LOCATION R882
J 0
(2425 1050);
DISPLAY 0.702128 (2425 1050);
PAINT YELLOW (2425 1050);
FORCEPROP 1 LASTPIN (2550 1050) $PN 1
J 0
(2562 1062);
DISPLAY 0.787234 (2562 1062);
PAINT MONO (2562 1062);
FORCEPROP 1 LASTPIN (2750 1050) $PN 2
J 0
(2712 1062);
DISPLAY 0.787234 (2712 1062);
PAINT MONO (2712 1062);
FORCEPROP 0 LAST CDS_LOCATION R882
J 0
(2425 1100);
DISPLAY 0.680851 (2425 1100);
DISPLAY INVISIBLE (2425 1100);
FORCEPROP 0 LAST $SEC 1
J 0
(2425 1100);
DISPLAY 0.680851 (2425 1100);
PAINT MONO (2425 1100);
DISPLAY INVISIBLE (2425 1100);
FORCEPROP 0 LAST CDS_SEC 1
J 0
(2425 1100);
DISPLAY 0.680851 (2425 1100);
DISPLAY INVISIBLE (2425 1100);
FORCEADD UNIVERSAL_GND..1
(2925 425);
FORCEPROP 3 LASTPIN (2925 475) SIG_NAME GND\g
J 0
(2935 485);
DISPLAY 0.659574 (2935 485);
PAINT MONO (2935 485);
DISPLAY INVISIBLE (2935 485);
FORCEPROP 2 LAST CDS_LIB logical_power
J 0
(2925 425);
DISPLAY INVISIBLE (2925 425);
FORCEPROP 1 LAST HDL_POWER GND
J 1
(2950 350);
DISPLAY 0.702128 (2950 350);
PAINT GREEN (2950 350);
DISPLAY INVISIBLE (2950 350);
FORCEPROP 1 LAST PATH I287
J 0
(3000 425);
DISPLAY 0.872340 (3000 425);
PAINT AQUA (3000 425);
DISPLAY INVISIBLE (3000 425);
FORCEADD SW_PUSHBUTTON4P_12_G34_H2..1
(-2700 4750);
FORCEPROP 1 LAST PART_NUMBER DHPDTSAM601
J 0
(-2774 4910);
DISPLAY 0.723404 (-2774 4910);
PAINT GREEN (-2774 4910);
FORCEPROP 1 LAST MATERIAL MECH
J 0
(-2774 4860);
DISPLAY 0.723404 (-2774 4860);
PAINT GREEN (-2774 4860);
FORCEPROP 2 LAST PART_TYPE SMLF
J 0
(-2750 5050);
DISPLAY 0.680851 (-2750 5050);
FORCEPROP 2 LAST VALUE SW4S_DTSAM-63N/K-S-Q-T/R
J 0
(-2750 5000);
DISPLAY 0.680851 (-2750 5000);
FORCEPROP 2 LAST CDS_LIB pure_quanta
J 0
(-2700 4750);
DISPLAY INVISIBLE (-2700 4750);
FORCEPROP 1 LAST PATH I292
J 0
(-2700 4750);
DISPLAY 0.723404 (-2700 4750);
PAINT GREEN (-2700 4750);
DISPLAY INVISIBLE (-2700 4750);
FORCEPROP 1 LAST CDS_LMAN_SYM_OUTLINE -75,100,75,-100
J 0
(-2700 4750);
DISPLAY 0.468085 (-2700 4750);
PAINT GREEN (-2700 4750);
DISPLAY INVISIBLE (-2700 4750);
FORCEPROP 1 LAST NEEDS_NO_SIZE TRUE
J 0
(-2625 4650);
DISPLAY 0.468085 (-2625 4650);
PAINT GREEN (-2625 4650);
DISPLAY INVISIBLE (-2625 4650);
FORCEPROP 1 LAST LOCATION SW6
J 0
(-2774 4955);
DISPLAY 0.723404 (-2774 4955);
PAINT GREEN (-2774 4955);
FORCEPROP 0 LASTPIN (-2925 4750) $PN 1
J 2
(-2935 4760);
DISPLAY 0.680851 (-2935 4760);
PAINT MONO (-2935 4760);
FORCEPROP 0 LASTPIN (-2475 4750) $PN 2
J 0
(-2465 4760);
DISPLAY 0.680851 (-2465 4760);
PAINT MONO (-2465 4760);
FORCEPROP 0 LASTPIN (-2925 4700) $PN 3
J 2
(-2935 4710);
DISPLAY 0.680851 (-2935 4710);
PAINT MONO (-2935 4710);
FORCEPROP 0 LASTPIN (-2475 4700) $PN 4
J 0
(-2465 4710);
DISPLAY 0.680851 (-2465 4710);
PAINT MONO (-2465 4710);
FORCEPROP 0 LAST $SEC 1
J 0
(-2750 5100);
PAINT MONO (-2750 5100);
DISPLAY INVISIBLE (-2750 5100);
FORCEPROP 0 LAST CDS_SEC 1
J 0
(-2750 5100);
PAINT MONO (-2750 5100);
DISPLAY INVISIBLE (-2750 5100);
FORCEADD SW_PUSHBUTTON4P_12_G34_H2..1
(1925 2550);
FORCEPROP 1 LAST PART_NUMBER DHPDTSAM601
J 0
(1851 2710);
DISPLAY 0.723404 (1851 2710);
PAINT GREEN (1851 2710);
FORCEPROP 2 LAST VALUE SW4S_DTSAM-63N/K-S-Q-T/R
J 0
(1875 2800);
DISPLAY 0.680851 (1875 2800);
FORCEPROP 1 LAST MATERIAL MECH
J 0
(1851 2660);
DISPLAY 0.723404 (1851 2660);
PAINT GREEN (1851 2660);
FORCEPROP 2 LAST PART_TYPE SMLF
J 0
(1875 2850);
DISPLAY 0.680851 (1875 2850);
FORCEPROP 2 LAST CDS_LIB pure_quanta
J 0
(1925 2550);
DISPLAY INVISIBLE (1925 2550);
FORCEPROP 1 LAST PATH I293
J 0
(1925 2550);
DISPLAY 0.723404 (1925 2550);
PAINT GREEN (1925 2550);
DISPLAY INVISIBLE (1925 2550);
FORCEPROP 1 LAST CDS_LMAN_SYM_OUTLINE -75,100,75,-100
J 0
(1925 2550);
DISPLAY 0.468085 (1925 2550);
PAINT GREEN (1925 2550);
DISPLAY INVISIBLE (1925 2550);
FORCEPROP 1 LAST NEEDS_NO_SIZE TRUE
J 0
(2000 2450);
DISPLAY 0.468085 (2000 2450);
PAINT GREEN (2000 2450);
DISPLAY INVISIBLE (2000 2450);
FORCEPROP 1 LAST LOCATION SW8
J 0
(1851 2755);
DISPLAY 0.723404 (1851 2755);
PAINT GREEN (1851 2755);
FORCEPROP 0 LASTPIN (1700 2550) $PN 1
J 2
(1690 2560);
DISPLAY 0.680851 (1690 2560);
PAINT MONO (1690 2560);
FORCEPROP 0 LASTPIN (2150 2550) $PN 2
J 0
(2160 2560);
DISPLAY 0.680851 (2160 2560);
PAINT MONO (2160 2560);
FORCEPROP 0 LASTPIN (1700 2500) $PN 3
J 2
(1690 2510);
DISPLAY 0.680851 (1690 2510);
PAINT MONO (1690 2510);
FORCEPROP 0 LASTPIN (2150 2500) $PN 4
J 0
(2160 2510);
DISPLAY 0.680851 (2160 2510);
PAINT MONO (2160 2510);
FORCEPROP 0 LAST $SEC 1
J 0
(1875 2900);
PAINT MONO (1875 2900);
DISPLAY INVISIBLE (1875 2900);
FORCEPROP 0 LAST CDS_SEC 1
J 0
(1875 2900);
PAINT MONO (1875 2900);
DISPLAY INVISIBLE (1875 2900);
FORCEADD Q_LED..1
R 2
(-1500 1625);
FORCEPROP 1 LAST PART_NUMBER BEBL0277D00
J 2
(-1400 1760);
DISPLAY 0.723404 (-1400 1760);
PAINT GREEN (-1400 1760);
FORCEPROP 1 LAST MATERIAL IC
J 2
(-1400 1705);
DISPLAY 0.723404 (-1400 1705);
PAINT GREEN (-1400 1705);
FORCEPROP 2 LAST PACK_TYPE THLF
J 2
(-1400 1850);
DISPLAY 0.680851 (-1400 1850);
FORCEPROP 2 LAST MANUF_PN HV-312470/260/SUBD-TR1
J 2
(-1400 1900);
DISPLAY 0.680851 (-1400 1900);
FORCEPROP 2 LAST COLOR LED_BLUE
J 2
(-1400 1950);
DISPLAY 0.680851 (-1400 1950);
FORCEPROP 1 LAST NEEDS_NO_SIZE TRUE
J 2
(-1500 1625);
DISPLAY 0.468085 (-1500 1625);
PAINT GREEN (-1500 1625);
DISPLAY INVISIBLE (-1500 1625);
FORCEPROP 1 LAST PATH I294
J 2
(-1625 1705);
DISPLAY 0.723404 (-1625 1705);
PAINT GREEN (-1625 1705);
DISPLAY INVISIBLE (-1625 1705);
FORCEPROP 2 LAST CDS_LIB pure_quanta
J 0
(-1500 1625);
DISPLAY INVISIBLE (-1500 1625);
FORCEPROP 1 LAST LOCATION D21
J 2
(-1400 1810);
DISPLAY 0.723404 (-1400 1810);
PAINT GREEN (-1400 1810);
FORCEPROP 0 LASTPIN (-1350 1625) $PN A
J 0
(-1340 1635);
DISPLAY 0.680851 (-1340 1635);
PAINT MONO (-1340 1635);
FORCEPROP 0 LASTPIN (-1650 1625) $PN C
J 2
(-1660 1635);
DISPLAY 0.680851 (-1660 1635);
PAINT MONO (-1660 1635);
FORCEPROP 0 LAST $SEC 1
J 0
(-1400 2000);
DISPLAY 0.680851 (-1400 2000);
PAINT MONO (-1400 2000);
DISPLAY INVISIBLE (-1400 2000);
FORCEPROP 0 LAST CDS_SEC 1
J 0
(-1400 2000);
DISPLAY 0.680851 (-1400 2000);
DISPLAY INVISIBLE (-1400 2000);
FORCEADD Q_LED..1
R 2
(-550 100);
FORCEPROP 1 LAST PART_NUMBER BEBL0277D00
J 2
(-450 235);
DISPLAY 0.723404 (-450 235);
PAINT GREEN (-450 235);
FORCEPROP 1 LAST MATERIAL IC
J 2
(-450 180);
DISPLAY 0.723404 (-450 180);
PAINT GREEN (-450 180);
FORCEPROP 2 LAST PACK_TYPE THLF
J 2
(-450 325);
DISPLAY 0.680851 (-450 325);
FORCEPROP 2 LAST MANUF_PN HV-312470/260/SUBD-TR1
J 2
(-450 375);
DISPLAY 0.680851 (-450 375);
FORCEPROP 2 LAST COLOR LED_BLUE
J 2
(-450 425);
DISPLAY 0.680851 (-450 425);
FORCEPROP 2 LAST CDS_LIB pure_quanta
J 0
(-550 100);
DISPLAY INVISIBLE (-550 100);
FORCEPROP 1 LAST PATH I295
J 2
(-675 180);
DISPLAY 0.723404 (-675 180);
PAINT GREEN (-675 180);
DISPLAY INVISIBLE (-675 180);
FORCEPROP 1 LAST NEEDS_NO_SIZE TRUE
J 2
(-550 100);
DISPLAY 0.468085 (-550 100);
PAINT GREEN (-550 100);
DISPLAY INVISIBLE (-550 100);
FORCEPROP 1 LAST LOCATION D22
J 2
(-450 285);
DISPLAY 0.723404 (-450 285);
PAINT GREEN (-450 285);
FORCEPROP 0 LASTPIN (-400 100) $PN A
J 0
(-390 110);
DISPLAY 0.680851 (-390 110);
PAINT MONO (-390 110);
FORCEPROP 0 LASTPIN (-700 100) $PN C
J 2
(-710 110);
DISPLAY 0.680851 (-710 110);
PAINT MONO (-710 110);
FORCEPROP 0 LAST $SEC 1
J 0
(-450 475);
DISPLAY 0.680851 (-450 475);
PAINT MONO (-450 475);
DISPLAY INVISIBLE (-450 475);
FORCEPROP 0 LAST CDS_SEC 1
J 0
(-450 475);
DISPLAY 0.680851 (-450 475);
DISPLAY INVISIBLE (-450 475);
FORCEADD UNIVERSAL_GND..1
(-1300 4025);
FORCEPROP 3 LASTPIN (-1300 4075) SIG_NAME GND\g
J 0
(-1290 4085);
DISPLAY 0.659574 (-1290 4085);
PAINT MONO (-1290 4085);
DISPLAY INVISIBLE (-1290 4085);
FORCEPROP 1 LAST HDL_POWER GND
J 1
(-1275 3950);
DISPLAY 0.702128 (-1275 3950);
PAINT GREEN (-1275 3950);
DISPLAY INVISIBLE (-1275 3950);
FORCEPROP 2 LAST CDS_LIB logical_power
J 0
(-1300 4025);
DISPLAY INVISIBLE (-1300 4025);
FORCEPROP 1 LAST PATH I30
J 0
(-1225 4025);
DISPLAY 0.872340 (-1225 4025);
PAINT AQUA (-1225 4025);
DISPLAY INVISIBLE (-1225 4025);
FORCEADD OFFPAGE..2
(925 4650);
FORCEPROP 2 LAST $XR3 34 
J 0
(1384 4650);
DISPLAY 0.638298 (1384 4650);
PAINT MONO (1384 4650);
FORCEPROP 2 LAST $XR2 15 
J 0
(1294 4650);
DISPLAY 0.638298 (1294 4650);
PAINT MONO (1294 4650);
FORCEPROP 2 LAST $XR1 11 
J 0
(1204 4650);
DISPLAY 0.638298 (1204 4650);
PAINT MONO (1204 4650);
FORCEPROP 2 LAST $XR0 10 
J 0
(1114 4650);
DISPLAY 0.638298 (1114 4650);
PAINT MONO (1114 4650);
FORCEPROP 2 LAST CDS_LIB standard
J 0
(925 4650);
DISPLAY INVISIBLE (925 4650);
FORCEPROP 1 LAST OFFPAGE TRUE
J 0
(1250 4525);
DISPLAY 0.872340 (1250 4525);
PAINT GREEN (1250 4525);
DISPLAY INVISIBLE (1250 4525);
FORCEPROP 1 LAST COMMENT_BODY TRUE
J 0
(880 4555);
DISPLAY 0.872340 (880 4555);
PAINT PEACH (880 4555);
DISPLAY INVISIBLE (880 4555);
FORCEPROP 2 LAST PATH I31
J 0
(725 4700);
DISPLAY 1.021277 (725 4700);
DISPLAY INVISIBLE (725 4700);
FORCEADD Q_CAP..1
R 2
(-475 5050);
FORCEPROP 1 LAST PART_NUMBER CH4104K1B00
J 2
(-525 4825);
DISPLAY 0.510638 (-525 4825);
PAINT WHITE (-525 4825);
FORCEPROP 1 LAST PACK_TYPE 0402
J 2
(-525 4875);
DISPLAY 0.510638 (-525 4875);
PAINT SKYBLUE (-525 4875);
FORCEPROP 1 LAST VALUE 0.1UF
J 2
(-525 5075);
DISPLAY 0.510638 (-525 5075);
PAINT SKYBLUE (-525 5075);
FORCEPROP 1 LAST MATERIAL X7R
J 2
(-525 4925);
DISPLAY 0.510638 (-525 4925);
PAINT SKYBLUE (-525 4925);
FORCEPROP 1 LAST VOLTAGE 25V
J 2
(-525 5025);
DISPLAY 0.510638 (-525 5025);
PAINT SKYBLUE (-525 5025);
FORCEPROP 1 LAST TOLERANCE 10%
J 2
(-525 4975);
DISPLAY 0.510638 (-525 4975);
PAINT SKYBLUE (-525 4975);
FORCEPROP 2 LAST CDS_LIB pure_quanta
J 2
(-475 5050);
DISPLAY INVISIBLE (-475 5050);
FORCEPROP 1 LAST PATH I43
J 2
(-525 5200);
DISPLAY 0.978723 (-525 5200);
PAINT WHITE (-525 5200);
DISPLAY INVISIBLE (-525 5200);
FORCEPROP 1 LAST LOCATION C200
J 2
(-525 5125);
DISPLAY 0.702128 (-525 5125);
PAINT YELLOW (-525 5125);
FORCEPROP 1 LASTPIN (-475 5150) $PN 1
J 2
(-485 5130);
DISPLAY 0.808511 (-485 5130);
PAINT WHITE (-485 5130);
FORCEPROP 1 LASTPIN (-475 4950) $PN 2
J 2
(-485 4930);
DISPLAY 0.808511 (-485 4930);
PAINT WHITE (-485 4930);
FORCEPROP 2 LAST $SEC 1
J 2
(-525 5250);
DISPLAY 0.680851 (-525 5250);
PAINT MONO (-525 5250);
DISPLAY INVISIBLE (-525 5250);
FORCEPROP 0 LAST CDS_SEC 1
J 2
(-525 5250);
DISPLAY 0.680851 (-525 5250);
PAINT MONO (-525 5250);
DISPLAY INVISIBLE (-525 5250);
FORCEADD Q_CAP..1
(-1175 4375);
FORCEPROP 1 LAST VALUE 1UF
J 0
(-1125 4425);
DISPLAY 0.510638 (-1125 4425);
PAINT SKYBLUE (-1125 4425);
FORCEPROP 1 LAST VOLTAGE 25V
J 0
(-1125 4375);
DISPLAY 0.510638 (-1125 4375);
PAINT SKYBLUE (-1125 4375);
FORCEPROP 1 LAST MATERIAL X6S
J 0
(-1125 4275);
DISPLAY 0.510638 (-1125 4275);
PAINT SKYBLUE (-1125 4275);
FORCEPROP 1 LAST TOLERANCE 10%
J 0
(-1125 4325);
DISPLAY 0.510638 (-1125 4325);
PAINT SKYBLUE (-1125 4325);
FORCEPROP 1 LAST PACK_TYPE C0402
J 0
(-1150 4225);
DISPLAY 0.510638 (-1150 4225);
PAINT SKYBLUE (-1150 4225);
FORCEPROP 2 LAST CDS_LIB pure_quanta
J 0
(-1175 4375);
DISPLAY INVISIBLE (-1175 4375);
FORCEPROP 1 LAST PART_NUMBER CH5104KEB02
J 0
(-1125 4225);
DISPLAY 0.510638 (-1125 4225);
PAINT WHITE (-1125 4225);
DISPLAY INVISIBLE (-1125 4225);
FORCEPROP 1 LAST PATH I44
J 0
(-1125 4525);
DISPLAY 0.978723 (-1125 4525);
PAINT WHITE (-1125 4525);
DISPLAY INVISIBLE (-1125 4525);
FORCEPROP 1 LAST LOCATION C198
J 0
(-1125 4475);
DISPLAY 0.702128 (-1125 4475);
PAINT YELLOW (-1125 4475);
FORCEPROP 1 LASTPIN (-1175 4475) $PN 1
J 0
(-1165 4455);
DISPLAY 0.808511 (-1165 4455);
PAINT WHITE (-1165 4455);
FORCEPROP 1 LASTPIN (-1175 4275) $PN 2
J 0
(-1165 4255);
DISPLAY 0.808511 (-1165 4255);
PAINT WHITE (-1165 4255);
FORCEPROP 2 LAST $SEC 1
J 0
(-1125 4575);
DISPLAY 0.680851 (-1125 4575);
PAINT MONO (-1125 4575);
DISPLAY INVISIBLE (-1125 4575);
FORCEPROP 0 LAST CDS_SEC 1
J 0
(-1125 4575);
DISPLAY 0.680851 (-1125 4575);
PAINT MONO (-1125 4575);
DISPLAY INVISIBLE (-1125 4575);
FORCEADD VCCAUX15..1
(-475 5250);
FORCEPROP 3 LASTPIN (-475 5200) SIG_NAME P3V3_AUX\g
J 0
(-465 5210);
DISPLAY 0.659574 (-465 5210);
PAINT MONO (-465 5210);
DISPLAY INVISIBLE (-465 5210);
FORCEPROP 1 LAST HDL_POWER P3V3_AUX
J 1
(-475 5300);
DISPLAY 0.702128 (-475 5300);
PAINT GREEN (-475 5300);
FORCEPROP 2 LAST CDS_LIB logical_power
J 0
(-475 5250);
DISPLAY INVISIBLE (-475 5250);
FORCEPROP 1 LAST PATH I45
J 0
(-425 5275);
DISPLAY 0.872340 (-425 5275);
PAINT AQUA (-425 5275);
DISPLAY INVISIBLE (-425 5275);
FORCEADD UNIVERSAL_GND..1
(-475 4825);
FORCEPROP 3 LASTPIN (-475 4875) SIG_NAME GND\g
J 0
(-465 4885);
DISPLAY 0.659574 (-465 4885);
PAINT MONO (-465 4885);
DISPLAY INVISIBLE (-465 4885);
FORCEPROP 2 LAST CDS_LIB logical_power
J 0
(-475 4825);
DISPLAY INVISIBLE (-475 4825);
FORCEPROP 1 LAST HDL_POWER GND
J 1
(-450 4750);
DISPLAY 0.702128 (-450 4750);
PAINT GREEN (-450 4750);
DISPLAY INVISIBLE (-450 4750);
FORCEPROP 1 LAST PATH I46
J 0
(-400 4825);
DISPLAY 0.872340 (-400 4825);
PAINT AQUA (-400 4825);
DISPLAY INVISIBLE (-400 4825);
FORCEADD OFFPAGE..2
(850 3250);
FORCEPROP 2 LAST $XR0 15 
J 0
(1039 3250);
DISPLAY 0.638298 (1039 3250);
PAINT MONO (1039 3250);
FORCEPROP 1 LAST OFFPAGE TRUE
J 0
(1175 3125);
DISPLAY 0.872340 (1175 3125);
PAINT GREEN (1175 3125);
DISPLAY INVISIBLE (1175 3125);
FORCEPROP 1 LAST COMMENT_BODY TRUE
J 0
(805 3155);
DISPLAY 0.872340 (805 3155);
PAINT PEACH (805 3155);
DISPLAY INVISIBLE (805 3155);
FORCEPROP 2 LAST PATH I48
J 0
(1025 3325);
DISPLAY 1.021277 (1025 3325);
DISPLAY INVISIBLE (1025 3325);
FORCEPROP 2 LAST CDS_LIB standard
J 0
(850 3250);
DISPLAY INVISIBLE (850 3250);
FORCEADD 74LVC1G17GW..1
(-125 3250);
FORCEPROP 1 LAST PART_NUMBER AL1G0017K01
J 0
(-259 3484);
DISPLAY 0.510638 (-259 3484);
PAINT WHITE (-259 3484);
FORCEPROP 2 LAST VALUE 74LVC1G17GW
J 0
(-250 3600);
DISPLAY 0.510638 (-250 3600);
PAINT SKYBLUE (-250 3600);
FORCEPROP 2 LAST PART_TYPE SMLF
J 0
(-250 3650);
DISPLAY 0.510638 (-250 3650);
PAINT SKYBLUE (-250 3650);
FORCEPROP 1 LAST MATERIAL IC
J 0
(-259 3404);
DISPLAY 0.510638 (-259 3404);
PAINT SKYBLUE (-259 3404);
FORCEPROP 1 LAST PATH I49
J 0
(0 3100);
DISPLAY 0.723404 (0 3100);
PAINT GREEN (0 3100);
DISPLAY INVISIBLE (0 3100);
FORCEPROP 1 LAST CDS_LMAN_SYM_OUTLINE -125,150,125,-150
J 0
(-125 3250);
DISPLAY 0.468085 (-125 3250);
PAINT GREEN (-125 3250);
DISPLAY INVISIBLE (-125 3250);
FORCEPROP 1 LAST PIN_NAMES_ROTATE True
J 0
(-125 3250);
DISPLAY 0.489362 (-125 3250);
PAINT GREEN (-125 3250);
DISPLAY INVISIBLE (-125 3250);
FORCEPROP 2 LAST CDS_LIB pure_quanta
J 0
(-125 3250);
DISPLAY INVISIBLE (-125 3250);
FORCEPROP 1 LAST LOCATION U32
J 0
(-259 3559);
DISPLAY 0.702128 (-259 3559);
PAINT YELLOW (-259 3559);
FORCEPROP 0 LASTPIN (-300 3250) $PN 2
J 2
(-310 3260);
DISPLAY 0.680851 (-310 3260);
PAINT MONO (-310 3260);
FORCEPROP 0 LASTPIN (-300 3150) $PN 3
J 2
(-310 3160);
DISPLAY 0.680851 (-310 3160);
PAINT MONO (-310 3160);
FORCEPROP 0 LASTPIN (50 3150) $PN 1
J 0
(60 3160);
DISPLAY 0.680851 (60 3160);
PAINT MONO (60 3160);
FORCEPROP 0 LASTPIN (-300 3350) $PN 5
J 2
(-310 3360);
DISPLAY 0.680851 (-310 3360);
PAINT MONO (-310 3360);
FORCEPROP 0 LASTPIN (50 3250) $PN 4
J 0
(60 3260);
DISPLAY 0.680851 (60 3260);
PAINT MONO (60 3260);
FORCEPROP 0 LAST $SEC 1
J 0
(-250 3675);
DISPLAY 0.680851 (-250 3675);
PAINT MONO (-250 3675);
DISPLAY INVISIBLE (-250 3675);
FORCEPROP 0 LAST CDS_SEC 1
J 0
(-250 3675);
DISPLAY 1.021277 (-250 3675);
DISPLAY INVISIBLE (-250 3675);
FORCEADD VCCAUX15..1
(-450 3850);
FORCEPROP 3 LASTPIN (-450 3800) SIG_NAME P3V3_AUX\g
J 0
(-440 3810);
DISPLAY 0.659574 (-440 3810);
PAINT MONO (-440 3810);
DISPLAY INVISIBLE (-440 3810);
FORCEPROP 1 LAST HDL_POWER P3V3_AUX
J 1
(-450 3900);
DISPLAY 0.702128 (-450 3900);
PAINT GREEN (-450 3900);
FORCEPROP 2 LAST CDS_LIB logical_power
J 0
(-450 3850);
DISPLAY INVISIBLE (-450 3850);
FORCEPROP 1 LAST PATH I50
J 0
(-400 3875);
DISPLAY 0.872340 (-400 3875);
PAINT AQUA (-400 3875);
DISPLAY INVISIBLE (-400 3875);
FORCEADD Q_CAP..1
R 2
(-450 3650);
FORCEPROP 1 LAST PART_NUMBER CH4104K1B00
J 2
(-500 3425);
DISPLAY 0.510638 (-500 3425);
PAINT WHITE (-500 3425);
FORCEPROP 1 LAST VALUE 0.1UF
J 2
(-500 3675);
DISPLAY 0.510638 (-500 3675);
PAINT SKYBLUE (-500 3675);
FORCEPROP 1 LAST PACK_TYPE 0402
J 2
(-500 3475);
DISPLAY 0.510638 (-500 3475);
PAINT SKYBLUE (-500 3475);
FORCEPROP 1 LAST VOLTAGE 25V
J 2
(-500 3625);
DISPLAY 0.510638 (-500 3625);
PAINT SKYBLUE (-500 3625);
FORCEPROP 1 LAST MATERIAL X7R
J 2
(-500 3525);
DISPLAY 0.510638 (-500 3525);
PAINT SKYBLUE (-500 3525);
FORCEPROP 1 LAST TOLERANCE 10%
J 2
(-500 3575);
DISPLAY 0.510638 (-500 3575);
PAINT SKYBLUE (-500 3575);
FORCEPROP 2 LAST CDS_LIB pure_quanta
J 2
(-450 3650);
DISPLAY INVISIBLE (-450 3650);
FORCEPROP 1 LAST PATH I51
J 2
(-500 3800);
DISPLAY 0.978723 (-500 3800);
PAINT WHITE (-500 3800);
DISPLAY INVISIBLE (-500 3800);
FORCEPROP 1 LAST LOCATION C201
J 2
(-500 3725);
DISPLAY 0.702128 (-500 3725);
PAINT YELLOW (-500 3725);
FORCEPROP 1 LASTPIN (-450 3750) $PN 1
J 2
(-460 3730);
DISPLAY 0.808511 (-460 3730);
PAINT WHITE (-460 3730);
FORCEPROP 1 LASTPIN (-450 3550) $PN 2
J 2
(-460 3530);
DISPLAY 0.808511 (-460 3530);
PAINT WHITE (-460 3530);
FORCEPROP 2 LAST $SEC 1
J 2
(-500 3850);
DISPLAY 0.680851 (-500 3850);
PAINT MONO (-500 3850);
DISPLAY INVISIBLE (-500 3850);
FORCEPROP 0 LAST CDS_SEC 1
J 2
(-500 3850);
DISPLAY 0.680851 (-500 3850);
PAINT MONO (-500 3850);
DISPLAY INVISIBLE (-500 3850);
FORCEADD UNIVERSAL_GND..1
(-450 3425);
FORCEPROP 3 LASTPIN (-450 3475) SIG_NAME GND\g
J 0
(-440 3485);
DISPLAY 0.659574 (-440 3485);
PAINT MONO (-440 3485);
DISPLAY INVISIBLE (-440 3485);
FORCEPROP 1 LAST PATH I52
J 0
(-375 3425);
DISPLAY 0.872340 (-375 3425);
PAINT AQUA (-375 3425);
DISPLAY INVISIBLE (-375 3425);
FORCEPROP 1 LAST HDL_POWER GND
J 1
(-425 3350);
DISPLAY 0.702128 (-425 3350);
PAINT GREEN (-425 3350);
DISPLAY INVISIBLE (-425 3350);
FORCEPROP 2 LAST CDS_LIB logical_power
J 0
(-450 3425);
DISPLAY INVISIBLE (-450 3425);
FORCEADD Q_CAP..1
(-1150 2975);
FORCEPROP 1 LAST PACK_TYPE C0402
J 0
(-1125 2825);
DISPLAY 0.510638 (-1125 2825);
PAINT SKYBLUE (-1125 2825);
FORCEPROP 1 LAST VALUE 1UF
J 0
(-1100 3025);
DISPLAY 0.510638 (-1100 3025);
PAINT SKYBLUE (-1100 3025);
FORCEPROP 1 LAST VOLTAGE 25V
J 0
(-1100 2975);
DISPLAY 0.510638 (-1100 2975);
PAINT SKYBLUE (-1100 2975);
FORCEPROP 1 LAST MATERIAL X6S
J 0
(-1100 2875);
DISPLAY 0.510638 (-1100 2875);
PAINT SKYBLUE (-1100 2875);
FORCEPROP 1 LAST TOLERANCE 10%
J 0
(-1100 2925);
DISPLAY 0.510638 (-1100 2925);
PAINT SKYBLUE (-1100 2925);
FORCEPROP 1 LAST PATH I55
J 0
(-1100 3125);
DISPLAY 0.978723 (-1100 3125);
PAINT WHITE (-1100 3125);
DISPLAY INVISIBLE (-1100 3125);
FORCEPROP 1 LAST PART_NUMBER CH5104KEB02
J 0
(-1100 2825);
DISPLAY 0.510638 (-1100 2825);
PAINT WHITE (-1100 2825);
DISPLAY INVISIBLE (-1100 2825);
FORCEPROP 2 LAST CDS_LIB pure_quanta
J 0
(-1150 2975);
DISPLAY INVISIBLE (-1150 2975);
FORCEPROP 1 LAST LOCATION C199
J 0
(-1100 3075);
DISPLAY 0.702128 (-1100 3075);
PAINT YELLOW (-1100 3075);
FORCEPROP 1 LASTPIN (-1150 3075) $PN 1
J 0
(-1140 3055);
DISPLAY 0.808511 (-1140 3055);
PAINT WHITE (-1140 3055);
FORCEPROP 1 LASTPIN (-1150 2875) $PN 2
J 0
(-1140 2855);
DISPLAY 0.808511 (-1140 2855);
PAINT WHITE (-1140 2855);
FORCEPROP 2 LAST $SEC 1
J 0
(-1100 3175);
DISPLAY 0.680851 (-1100 3175);
PAINT MONO (-1100 3175);
DISPLAY INVISIBLE (-1100 3175);
FORCEPROP 0 LAST CDS_SEC 1
J 0
(-1100 3175);
DISPLAY 0.680851 (-1100 3175);
PAINT MONO (-1100 3175);
DISPLAY INVISIBLE (-1100 3175);
FORCEADD Q_RES..2
(-1150 3625);
FORCEPROP 1 LAST PART_NUMBER CS28202JB05
J 0
(-1110 3500);
DISPLAY 0.510638 (-1110 3500);
PAINT WHITE (-1110 3500);
FORCEPROP 1 LAST PACK_TYPE 0402LF
J 0
(-1110 3450);
DISPLAY 0.510638 (-1110 3450);
PAINT SKYBLUE (-1110 3450);
FORCEPROP 1 LAST VALUE 8.2K
J 0
(-1105 3700);
DISPLAY 0.510638 (-1105 3700);
PAINT SKYBLUE (-1105 3700);
FORCEPROP 1 LAST TOLERANCE 5%
J 0
(-1105 3650);
DISPLAY 0.510638 (-1105 3650);
PAINT SKYBLUE (-1105 3650);
FORCEPROP 1 LAST WATTAGE 1/16W
J 0
(-1110 3600);
DISPLAY 0.510638 (-1110 3600);
PAINT SKYBLUE (-1110 3600);
FORCEPROP 1 LAST MATERIAL CHIP
J 0
(-1110 3550);
DISPLAY 0.510638 (-1110 3550);
PAINT SKYBLUE (-1110 3550);
FORCEPROP 1 LAST PATH I82
J 0
(-1100 3800);
DISPLAY 0.978723 (-1100 3800);
PAINT WHITE (-1100 3800);
DISPLAY INVISIBLE (-1100 3800);
FORCEPROP 2 LAST CDS_LIB pure_quanta
J 0
(-1150 3625);
DISPLAY INVISIBLE (-1150 3625);
FORCEPROP 1 LAST LOCATION R504
J 0
(-1105 3750);
DISPLAY 0.702128 (-1105 3750);
PAINT YELLOW (-1105 3750);
FORCEPROP 1 LASTPIN (-1150 3725) $PN 1
J 0
(-1145 3687);
DISPLAY 0.808511 (-1145 3687);
PAINT WHITE (-1145 3687);
FORCEPROP 1 LASTPIN (-1150 3525) $PN 2
J 0
(-1145 3535);
DISPLAY 0.808511 (-1145 3535);
PAINT WHITE (-1145 3535);
FORCEPROP 0 LAST $SEC 1
J 0
(-1100 3800);
DISPLAY 0.680851 (-1100 3800);
PAINT MONO (-1100 3800);
DISPLAY INVISIBLE (-1100 3800);
FORCEPROP 0 LAST CDS_SEC 1
J 0
(-1100 3800);
DISPLAY 0.680851 (-1100 3800);
DISPLAY INVISIBLE (-1100 3800);
FORCEADD VCCAUX15..1
(-1150 3850);
FORCEPROP 3 LASTPIN (-1150 3800) SIG_NAME P3V3_AUX\g
J 0
(-1140 3810);
DISPLAY 0.659574 (-1140 3810);
PAINT MONO (-1140 3810);
DISPLAY INVISIBLE (-1140 3810);
FORCEPROP 1 LAST HDL_POWER P3V3_AUX
J 1
(-1150 3900);
DISPLAY 0.702128 (-1150 3900);
PAINT GREEN (-1150 3900);
FORCEPROP 1 LAST PATH I83
J 0
(-1100 3875);
DISPLAY 0.872340 (-1100 3875);
PAINT AQUA (-1100 3875);
DISPLAY INVISIBLE (-1100 3875);
FORCEPROP 2 LAST CDS_LIB logical_power
J 0
(-1150 3850);
DISPLAY INVISIBLE (-1150 3850);
FORCEADD Q_RES..2
(-1175 5050);
FORCEPROP 1 LAST VALUE 8.2K
J 0
(-1130 5125);
DISPLAY 0.510638 (-1130 5125);
PAINT SKYBLUE (-1130 5125);
FORCEPROP 1 LAST PART_NUMBER CS28202JB05
J 0
(-1135 4925);
DISPLAY 0.510638 (-1135 4925);
PAINT WHITE (-1135 4925);
FORCEPROP 1 LAST WATTAGE 1/16W
J 0
(-1135 5025);
DISPLAY 0.510638 (-1135 5025);
PAINT SKYBLUE (-1135 5025);
FORCEPROP 1 LAST MATERIAL CHIP
J 0
(-1135 4975);
DISPLAY 0.510638 (-1135 4975);
PAINT SKYBLUE (-1135 4975);
FORCEPROP 1 LAST TOLERANCE 5%
J 0
(-1130 5075);
DISPLAY 0.510638 (-1130 5075);
PAINT SKYBLUE (-1130 5075);
FORCEPROP 1 LAST PACK_TYPE 0402LF
J 0
(-1135 4875);
DISPLAY 0.510638 (-1135 4875);
PAINT SKYBLUE (-1135 4875);
FORCEPROP 2 LAST CDS_LIB pure_quanta
J 0
(-1175 5050);
DISPLAY INVISIBLE (-1175 5050);
FORCEPROP 1 LAST PATH I89
J 0
(-1125 5225);
DISPLAY 0.978723 (-1125 5225);
PAINT WHITE (-1125 5225);
DISPLAY INVISIBLE (-1125 5225);
FORCEPROP 1 LAST LOCATION R768
J 0
(-1130 5175);
DISPLAY 0.702128 (-1130 5175);
PAINT YELLOW (-1130 5175);
FORCEPROP 1 LASTPIN (-1175 5150) $PN 1
J 0
(-1170 5112);
DISPLAY 0.808511 (-1170 5112);
PAINT WHITE (-1170 5112);
FORCEPROP 1 LASTPIN (-1175 4950) $PN 2
J 0
(-1170 4960);
DISPLAY 0.808511 (-1170 4960);
PAINT WHITE (-1170 4960);
FORCEPROP 0 LAST $SEC 1
J 0
(-1125 5225);
DISPLAY 0.680851 (-1125 5225);
PAINT MONO (-1125 5225);
DISPLAY INVISIBLE (-1125 5225);
FORCEPROP 0 LAST CDS_SEC 1
J 0
(-1125 5225);
DISPLAY 0.680851 (-1125 5225);
DISPLAY INVISIBLE (-1125 5225);
FORCEADD VCCAUX15..1
(-1175 5250);
FORCEPROP 3 LASTPIN (-1175 5200) SIG_NAME P3V3_AUX\g
J 0
(-1165 5210);
DISPLAY 0.659574 (-1165 5210);
PAINT MONO (-1165 5210);
DISPLAY INVISIBLE (-1165 5210);
FORCEPROP 1 LAST HDL_POWER P3V3_AUX
J 1
(-1175 5300);
DISPLAY 0.702128 (-1175 5300);
PAINT GREEN (-1175 5300);
FORCEPROP 2 LAST CDS_LIB logical_power
J 0
(-1175 5250);
DISPLAY INVISIBLE (-1175 5250);
FORCEPROP 1 LAST PATH I90
J 0
(-1125 5275);
DISPLAY 0.872340 (-1125 5275);
PAINT AQUA (-1125 5275);
DISPLAY INVISIBLE (-1125 5275);
FORCEADD QUANTA_TITLE_BLOCK_C..1
(5525 -1175);
FORCEPROP 0 LAST CDS_CON_LAST_MODIFIED Fri Aug 25 17:25:48 2023
J 0
(3640 -1160);
DISPLAY INVISIBLE (3640 -1160);
FORCEPROP 2 LAST Q_DEPT 
J 1
(1762 -1126);
DISPLAY 1.957447 (1762 -1126);
PAINT GREEN (1762 -1126);
FORCEPROP 1 LAST CUSTOM_TXT_CDS <CON_LAST_MODIFIED>
J 0
(3640 -1160);
DISPLAY 0.978723 (3640 -1160);
FORCEPROP 2 LAST CUSTOM_TXT_CDS <XR_PAGE_TITLE>
J 0
(-2365 4075);
DISPLAY 0.638298 (-2365 4075);
PAINT PINK (-2365 4075);
DISPLAY INVISIBLE (-2365 4075);
FORCEPROP 1 LAST CUSTOM_TXT_CDS <NAME_2>
J 0
(2350 -1125);
FORCEPROP 1 LAST CUSTOM_TXT_CDS <NAME_1>
J 0
(2350 -1000);
FORCEPROP 1 LAST CUSTOM_TXT_CDS <Q_NUMBER>
J 0
(4122 -1072);
DISPLAY 1.212766 (4122 -1072);
FORCEPROP 1 LAST CUSTOM_TXT_CDS <Q_PROJ>
J 0
(3143 -1073);
DISPLAY 1.212766 (3143 -1073);
FORCEPROP 1 LAST CUSTOM_TXT_CDS <Q_REV>
J 0
(5341 -1072);
DISPLAY 1.212766 (5341 -1072);
FORCEPROP 1 LAST CUSTOM_TXT_CDS <CON_PAGE_NUM> OF <CON_TOTAL_PAGES>
J 0
(5079 -1157);
DISPLAY 0.978723 (5079 -1157);
FORCEPROP 1 LAST Q_TITLE PWR BTN & BATTERY
J 0
(-3816 -1149);
DISPLAY 2.446809 (-3816 -1149);
PAINT GREEN (-3816 -1149);
FORCEPROP 2 LAST CDS_XR_PAGE_TITLE CR-50 : @SCM_LIB.SCM(SCH_1):PAGE50
J 0
(-2365 4075);
DISPLAY 0.638298 (-2365 4075);
PAINT PINK (-2365 4075);
DISPLAY INVISIBLE (-2365 4075);
FORCEPROP 2 LAST CDS_LIB pure_quanta
J 0
(5525 -1175);
DISPLAY INVISIBLE (5525 -1175);
FORCEPROP 1 LAST CDS_LMAN_SYM_OUTLINE -9475,6775,100,-125
J 0
(5525 -1175);
DISPLAY 0.468085 (5525 -1175);
PAINT GREEN (5525 -1175);
DISPLAY INVISIBLE (5525 -1175);
FORCEPROP 2 LAST PAGE_BORDER TRUE
J 0
(-2365 4075);
DISPLAY 0.638298 (-2365 4075);
PAINT PINK (-2365 4075);
DISPLAY INVISIBLE (-2365 4075);
FORCEPROP 1 LAST COMMENT_BODY TRUE
J 0
(5537 -1188);
DISPLAY 0.978723 (5537 -1188);
PAINT PEACH (5537 -1188);
DISPLAY INVISIBLE (5537 -1188);
FORCEADD DNS..2
(4025 3275);
PAINT RED (4025 3275);
FORCEPROP 1 LAST COMMENT_BODY TRUE
R 1
J 0
(4100 3050);
DISPLAY 0.872340 (4100 3050);
PAINT PEACH (4100 3050);
DISPLAY INVISIBLE (4100 3050);
FORCEPROP 2 LAST CDS_LIB mstr_misc
J 0
(4025 3275);
DISPLAY INVISIBLE (4025 3275);
FORCEADD DNS..2
(3675 3675);
PAINT RED (3675 3675);
FORCEPROP 1 LAST COMMENT_BODY TRUE
R 1
J 0
(3750 3450);
DISPLAY 0.872340 (3750 3450);
PAINT PEACH (3750 3450);
DISPLAY INVISIBLE (3750 3450);
FORCEPROP 2 LAST CDS_LIB mstr_misc
J 0
(3675 3675);
DISPLAY INVISIBLE (3675 3675);
FORCEADD DNS..2
(3000 3650);
PAINT RED (3000 3650);
FORCEPROP 1 LAST COMMENT_BODY TRUE
R 1
J 0
(3075 3425);
DISPLAY 0.872340 (3075 3425);
PAINT PEACH (3075 3425);
DISPLAY INVISIBLE (3075 3425);
FORCEPROP 2 LAST CDS_LIB mstr_misc
J 0
(3000 3650);
DISPLAY INVISIBLE (3000 3650);
FORCEADD DNS..2
(2675 3250);
PAINT RED (2675 3250);
FORCEPROP 2 LAST CDS_LIB mstr_misc
J 0
(2675 3250);
DISPLAY INVISIBLE (2675 3250);
FORCEPROP 1 LAST COMMENT_BODY TRUE
R 1
J 0
(2750 3025);
DISPLAY 0.872340 (2750 3025);
PAINT PEACH (2750 3025);
DISPLAY INVISIBLE (2750 3025);
FORCEADD BOM_NOTE..1
(4275 1850);
FORCEPROP 0 LAST L2 D10 CHANGE TO BC8231ADZ01
J 0
(4125 1725);
DISPLAY 1.021277 (4125 1725);
PAINT GREEN (4125 1725);
FORCEPROP 1 LAST COMMENT_BODY TRUE
J 0
(4300 1950);
DISPLAY 0.978723 (4300 1950);
PAINT PEACH (4300 1950);
DISPLAY INVISIBLE (4300 1950);
FORCEPROP 2 LAST CDS_LIB logical_power
J 0
(4275 1850);
DISPLAY INVISIBLE (4275 1850);
FORCEADD DNS..2
(2975 3000);
PAINT RED (2975 3000);
FORCEPROP 1 LAST COMMENT_BODY TRUE
R 1
J 0
(3050 2775);
DISPLAY 0.872340 (3050 2775);
PAINT PEACH (3050 2775);
DISPLAY INVISIBLE (3050 2775);
FORCEPROP 2 LAST CDS_LIB mstr_misc
J 0
(2975 3000);
DISPLAY INVISIBLE (2975 3000);
FORCEADD DNS..2
(2950 1450);
PAINT RED (2950 1450);
FORCEPROP 2 LAST CDS_LIB mstr_misc
J 0
(2950 1450);
DISPLAY INVISIBLE (2950 1450);
FORCEPROP 1 LAST COMMENT_BODY TRUE
R 1
J 0
(3025 1225);
DISPLAY 0.872340 (3025 1225);
PAINT PEACH (3025 1225);
DISPLAY INVISIBLE (3025 1225);
WIRE 16 -1 (4650 4950)(4650 5225);
WIRE 16 -1 (4650 4800)(4650 4950);
WIRE 16 -1 (4075 4950)(4650 4950);
WIRE 16 -1 (3300 5250)(3300 5000);
WIRE 16 -1 (-475 5175)(-475 5200);
WIRE 16 -1 (-475 5175)(-375 5175);
WIRE 16 -1 (-475 5150)(-475 5175);
WIRE 16 -1 (-1175 5200)(-1175 5150);
WIRE 16 -1 (3000 3825)(3000 3775);
WIRE 16 -1 (3700 3800)(3700 3825);
WIRE 16 -1 (3700 3800)(3800 3800);
WIRE 16 -1 (3700 3775)(3700 3800);
WIRE 16 -1 (-450 3775)(-450 3800);
WIRE 16 -1 (-450 3775)(-350 3775);
WIRE 16 -1 (-450 3750)(-450 3775);
WIRE 16 -1 (950 2150)(950 1625);
WIRE 16 -1 (750 900)(750 1125);
WIRE 16 -1 (-1150 3800)(-1150 3725);
WIRE 16 -1 (3750 1575)(3750 1600);
WIRE 16 -1 (3750 1575)(3850 1575);
WIRE 16 -1 (3750 1550)(3750 1575);
WIRE 16 -1 (2975 1600)(2975 1550);
WIRE 16 -1 (4425 2225)(4425 2125);
WIRE 16 -1 (4250 2225)(4425 2225);
WIRE 16 -1 (3700 3500)(3700 3575);
WIRE 16 -1 (2875 2750)(2875 2700);
WIRE 16 -1 (2875 2750)(3000 2750);
WIRE 16 -1 (3800 1975)(3800 1875);
WIRE 16 -1 (3750 1275)(3750 1350);
WIRE 16 -1 (2925 525)(2925 475);
WIRE 16 -1 (2925 525)(3050 525);
WIRE 16 -1 (1600 2175)(1600 2325);
WIRE 16 -1 (-1575 -475)(-1575 -575);
WIRE 16 -1 (750 -300)(750 -475);
WIRE 16 -1 (-1825 1625)(-1825 1500);
WIRE 16 -1 (-1650 1625)(-1825 1625);
WIRE 16 -1 (-1400 2725)(-1400 2700);
WIRE 16 -1 (-1400 2725)(-1150 2725);
WIRE 16 -1 (-3175 2975)(-3175 3125);
WIRE 16 -1 (-450 3475)(-450 3550);
WIRE 16 -1 (-475 4875)(-475 4950);
WIRE 16 -1 (-3025 4375)(-3025 4525);
WIRE 16 -1 (-1300 4125)(-1300 4075);
WIRE 16 -1 (-1300 4125)(-1175 4125);
WIRE 16 -1 (4650 4600)(4650 4425);
WIRE 16 -1 (-3075 3350)(-3175 3350);
WIRE 16 -1 (-3075 3300)(-3175 3300);
WIRE 16 -1 (-3175 3350)(-3175 3300);
WIRE 16 -1 (-3175 3125)(-3175 3300);
WIRE 16 -1 (-3175 3125)(-2550 3125);
WIRE 16 -1 (-2550 3300)(-2550 3125);
WIRE 16 -1 (-2625 3300)(-2550 3300);
WIRE 16 -1 (3300 5000)(3875 5000);
WIRE 16 -1 (-2925 4750)(-3025 4750);
WIRE 16 -1 (-3025 4750)(-3025 4700);
WIRE 16 -1 (-2925 4700)(-3025 4700);
WIRE 16 -1 (-3025 4525)(-3025 4700);
WIRE 16 -1 (-2400 4525)(-3025 4525);
WIRE 16 -1 (-2400 4700)(-2400 4525);
WIRE 16 -1 (-2475 4700)(-2400 4700);
WIRE 16 -1 (-300 3150)(-375 3150);
WIRE 16 -1 (-375 3150)(-375 2725);
WIRE 16 -1 (-1150 2725)(-1150 2875);
WIRE 16 -1 (-375 2725)(-1150 2725);
WIRE 16 -1 (950 1625)(725 1625);
WIRE 16 -1 (3800 3375)(3850 3375);
WIRE 16 -1 (3800 3800)(3800 3375);
WIRE 16 -1 (1700 2550)(1600 2550);
WIRE 16 -1 (1600 2550)(1600 2500);
WIRE 16 -1 (1700 2500)(1600 2500);
WIRE 16 -1 (1600 2325)(1600 2500);
WIRE 16 -1 (2250 2325)(1600 2325);
WIRE 16 -1 (2250 2500)(2250 2325);
WIRE 16 -1 (2150 2500)(2250 2500);
WIRE 16 -1 (3850 3175)(3775 3175);
WIRE 16 -1 (3775 3175)(3775 2750);
WIRE 16 -1 (3000 2750)(3000 2900);
WIRE 16 -1 (3775 2750)(3000 2750);
WIRE 16 -1 (3900 950)(3825 950);
WIRE 16 -1 (3825 950)(3825 525);
WIRE 16 -1 (3050 525)(3050 675);
WIRE 16 -1 (3825 525)(3050 525);
WIRE 16 -1 (-325 4550)(-400 4550);
WIRE 16 -1 (-400 4550)(-400 4125);
WIRE 16 -1 (-1175 4125)(-1175 4275);
WIRE 16 -1 (-400 4125)(-1175 4125);
WIRE 16 -1 (-375 4750)(-325 4750);
WIRE 16 -1 (-375 5175)(-375 4750);
WIRE 16 -1 (-350 3350)(-300 3350);
WIRE 16 -1 (-350 3775)(-350 3350);
WIRE 16 -1 (3850 1150)(3900 1150);
WIRE 16 -1 (3850 1575)(3850 1150);
WIRE 16 -1 (3800 2225)(3800 2175);
WIRE 16 -1 (3950 2225)(3800 2225);
WIRE 16 -1 (2550 1050)(2400 1050);
WIRE 16 -1 (3800 2225)(3800 2550);
WIRE 16 -1 (3800 2550)(4000 2550);
WIRE 16 -1 (2150 2550)(2400 2550);
WIRE 16 -1 (3800 2550)(2400 2550);
WIRE 16 -1 (2400 1050)(2400 2550);
WIRE 16 -1 (2400 3275)(2400 2550);
FORCEPROP 2 LAST SIG_NAME REAR_AC_PWR_BTN
J 0
(3340 2560);
DISPLAY 0.851064 (3340 2560);
WIRE 16 -1 (2575 3275)(2400 3275);
WIRE 16 -1 (2975 1050)(2750 1050);
WIRE 16 -1 (2975 1050)(2975 1350);
WIRE 16 -1 (2975 1050)(3050 1050);
WIRE 16 -1 (3900 1050)(3050 1050);
FORCEPROP 2 LAST SIG_NAME REAR_AC_PWR_BMC_BTN_N
J 2
(3840 1060);
DISPLAY 0.808511 (3840 1060);
WIRE 16 -1 (3050 875)(3050 1050);
WIRE 16 3135 (5525 4175)(1475 4175);
WIRE 16 3135 (1475 4175)(1475 2575);
WIRE 16 2175 (1475 2575)(1450 2575);
WIRE 16 2175 (-3725 2575)(1450 2575);
WIRE 16 2175 (1450 2575)(1450 -800);
WIRE 16 2175 (-3725 2575)(-3725 -800);
WIRE 16 2175 (-3725 -800)(1450 -800);
FORCEPROP 0 LAST VOLTAGE 0
J 0
(-2175 -800);
PAINT SKYBLUE (-2175 -800);
DISPLAY INVISIBLE (-2175 -800);
FORCEPROP 0 LAST VOLTAGE 0
J 0
(-150 -800);
PAINT SKYBLUE (-150 -800);
DISPLAY INVISIBLE (-150 -800);
WIRE 16 -1 (50 3150)(500 3150);
FORCEPROP 2 LAST SIG_NAME TP_ID_BUF
J 2
(515 3160);
DISPLAY 0.808511 (515 3160);
PAINT WHITE (515 3160);
WIRE 16 -1 (-1575 100)(-1575 -75);
WIRE 16 -1 (-700 100)(-1575 100);
FORCEPROP 2 LAST SIG_NAME LED_D22_R1
J 0
(-1560 110);
DISPLAY 0.851064 (-1560 110);
WIRE 16 -1 (750 -100)(750 100);
WIRE 16 -1 (750 700)(750 100);
WIRE 16 -1 (-400 100)(750 100);
FORCEPROP 2 LAST SIG_NAME LED_D22_R
J 0
(-235 110);
DISPLAY 0.808511 (-235 110);
WIRE 16 -1 (-1350 1625)(-850 1625);
FORCEPROP 2 LAST SIG_NAME LED_D21_R3
J 0
(-1285 1635);
DISPLAY 0.851064 (-1285 1635);
WIRE 16 -1 (-2300 3775)(-3200 3775);
FORCEPROP 2 LAST SIG_NAME FM_DEBUG_RST_BTN_N
J 0
(-3160 3785);
DISPLAY 0.851064 (-3160 3785);
WIRE 16 -1 (-1575 5175)(-1900 5175);
WIRE 16 -1 (-1575 4750)(-2475 4750);
FORCEPROP 2 LAST SIG_NAME REAR_PWR_BTN_N
J 2
(-1735 4760);
DISPLAY 0.808511 (-1735 4760);
WIRE 16 -1 (-1575 4750)(-1575 5175);
WIRE 16 -1 (-1175 4750)(-1575 4750);
WIRE 16 -1 (-1175 4950)(-1175 4750);
WIRE 16 -1 (-1175 4750)(-1175 4650);
WIRE 16 -1 (-325 4650)(-1175 4650);
WIRE 16 -1 (-1175 4475)(-1175 4650);
WIRE 16 -1 (-1625 3775)(-2100 3775);
WIRE 16 -1 (-1625 3350)(-2625 3350);
WIRE 16 -1 (-1625 3350)(-1625 3775);
WIRE 16 -1 (-1150 3525)(-1150 3350);
WIRE 16 -1 (-1150 3350)(-1625 3350);
FORCEPROP 2 LAST SIG_NAME REAR_ID_RST_BTN_N
J 2
(-1760 3360);
DISPLAY 0.808511 (-1760 3360);
WIRE 16 -1 (-1150 3350)(-1150 3250);
WIRE 16 -1 (-300 3250)(-1150 3250);
WIRE 16 -1 (-1150 3075)(-1150 3250);
WIRE 16 -1 (4950 1050)(4300 1050);
FORCEPROP 2 LAST SIG_NAME AC_PWR_BMC_BTN_N
J 2
(4965 1060);
DISPLAY 0.808511 (4965 1060);
WIRE 16 -1 (4950 950)(4300 950);
FORCEPROP 2 LAST SIG_NAME NC_U57_P1
J 2
(4915 960);
DISPLAY 0.808511 (4915 960);
PAINT WHITE (4915 960);
WIRE 16 -1 (525 1625)(75 1625);
FORCEPROP 2 LAST SIG_NAME LED_D21_R1
J 0
(115 1635);
DISPLAY 0.851064 (115 1635);
WIRE 16 -1 (50 3250)(800 3250);
FORCEPROP 2 LAST SIG_NAME ID_RST_BTN_BMC_N
J 2
(740 3260);
DISPLAY 0.808511 (740 3260);
WIRE 16 -1 (3000 3275)(2775 3275);
WIRE 16 -1 (3000 3100)(3000 3275);
WIRE 16 -1 (3000 3275)(3000 3575);
WIRE 16 -1 (3850 3275)(3000 3275);
FORCEPROP 2 LAST SIG_NAME REAR_AC_PWR_BTN_N
J 2
(3715 3285);
DISPLAY 0.808511 (3715 3285);
WIRE 16 -1 (-125 1625)(-650 1625);
FORCEPROP 2 LAST SIG_NAME LED_D21_R2
J 0
(-585 1635);
DISPLAY 0.851064 (-585 1635);
WIRE 16 -1 (4200 2550)(4950 2550);
FORCEPROP 2 LAST SIG_NAME AC_PWR_BTN_N
J 2
(4890 2560);
DISPLAY 0.808511 (4890 2560);
WIRE 16 -1 (4900 3275)(4250 3275);
FORCEPROP 2 LAST SIG_NAME AC_PWR_BTN_R1_N
J 2
(4890 3285);
DISPLAY 0.808511 (4890 3285);
WIRE 16 -1 (4900 3175)(4250 3175);
FORCEPROP 2 LAST SIG_NAME NC_U16_P1
J 2
(4865 3185);
DISPLAY 0.808511 (4865 3185);
PAINT WHITE (4865 3185);
WIRE 16 -1 (3875 4900)(3275 4900);
FORCEPROP 2 LAST SIG_NAME P3V_BAT_R
J 0
(3340 4910);
DISPLAY 0.851064 (3340 4910);
WIRE 16 -1 (-2750 -325)(-1825 -325);
FORCEPROP 2 LAST SIG_NAME PWRGD_P1V0_AUX_DELAY
J 0
(-2700 -315);
DISPLAY 0.808511 (-2700 -315);
WIRE 16 -1 (875 4650)(75 4650);
FORCEPROP 2 LAST SIG_NAME PWR_BTN_BMC_N
J 2
(690 4660);
DISPLAY 0.808511 (690 4660);
WIRE 16 -1 (625 4550)(75 4550);
FORCEPROP 2 LAST SIG_NAME TP_PWR_BUF
J 2
(590 4560);
DISPLAY 0.808511 (590 4560);
PAINT WHITE (590 4560);
WIRE 16 -1 (-2100 5175)(-3050 5175);
FORCEPROP 2 LAST SIG_NAME FM_DEBUG_PWR_BTN_N
J 0
(-3010 5185);
DISPLAY 0.851064 (-3010 5185);
DOT 1 (1600 2500);
DOT 1 (1600 2325);
DOT 1 (-3025 4700);
DOT 1 (-450 3775);
DOT 1 (1450 2575);
DOT 1 (750 100);
DOT 1 (-3175 3300);
DOT 1 (-1150 3250);
DOT 1 (-3175 3125);
DOT 1 (-1625 3350);
DOT 1 (-1150 2725);
DOT 1 (4650 4950);
DOT 1 (-3025 4525);
DOT 1 (-1575 4750);
DOT 1 (-1175 4125);
DOT 1 (-1175 4750);
DOT 1 (-1175 4650);
DOT 1 (-475 5175);
DOT 1 (-1150 3350);
DOT 1 (3050 525);
DOT 1 (2975 1050);
DOT 1 (3050 1050);
DOT 1 (3750 1575);
DOT 1 (2400 2550);
DOT 1 (3000 2750);
DOT 1 (3000 3275);
DOT 1 (3800 2225);
DOT 1 (3800 2550);
DOT 1 (3700 3800);
FORCENOTE
P1V0 PWRGD LED
(-3450 600) 0;
DISPLAY LEFT (-3450 600);
DISPLAY 2.510638 (-3450 600);
PAINT WHITE (-3450 600);
FORCENOTE
SCM VIN LED
(-3475 2200) 0;
DISPLAY LEFT (-3475 2200);
DISPLAY 2.510638 (-3475 2200);
PAINT WHITE (-3475 2200);
FORCENOTE
RESET BUTTON
(-3750 3900) 0;
DISPLAY LEFT (-3750 3900);
DISPLAY 2.510638 (-3750 3900);
PAINT WHITE (-3750 3900);
FORCENOTE
ADD LED_20220804
(-3800 2600) 0;
DISPLAY LEFT (-3800 2600);
DISPLAY 1.595745 (-3800 2600);
PAINT WHITE (-3800 2600);
FORCENOTE
POWER BUTTON
(-3750 5300) 0;
DISPLAY LEFT (-3750 5300);
DISPLAY 2.510638 (-3750 5300);
PAINT WHITE (-3750 5300);
FORCENOTE
BATTERY
(1800 5225) 0;
DISPLAY LEFT (1800 5225);
DISPLAY 2.510638 (1800 5225);
PAINT WHITE (1800 5225);
FORCENOTE
ADD AC POWER BUTTON_20220804
(1475 4225) 0;
DISPLAY LEFT (1475 4225);
DISPLAY 1.595745 (1475 4225);
PAINT WHITE (1475 4225);
FORCENOTE
AC POWER BUTTON
(1500 4000) 0;
DISPLAY LEFT (1500 4000);
DISPLAY 2.510638 (1500 4000);
PAINT WHITE (1500 4000);
QUIT
